(kicad_sch
	(version 20250114)
	(generator "eeschema")
	(generator_version "9.0")
	(paper "A3")
	(title_block
		(title "OCuLink to 10GbE adapter")
		(date "2026-02-23")
		(rev "1.1.0")
		(company "Antmicro Ltd")
		(comment 1 "www.antmicro.com")
	)
	(text "OCuLink Connector"
		(exclude_from_sim no)
		(at 201.93 64.77 0)
		(effects
			(font
				(size 2.54 2.54)
				(thickness 0.508)
				(bold yes)
			)
		)
	)
	(junction
		(at 194.31 87.63)
		(diameter 0)
		(color 0 0 0 0)
	)
	(junction
		(at 257.81 110.49)
		(diameter 0)
		(color 0 0 0 0)
	)
	(junction
		(at 266.7 113.03)
		(diameter 0)
		(color 0 0 0 0)
	)
	(junction
		(at 250.19 115.57)
		(diameter 0)
		(color 0 0 0 0)
	)
	(junction
		(at 245.11 113.03)
		(diameter 0)
		(color 0 0 0 0)
	)
	(junction
		(at 163.83 176.53)
		(diameter 0)
		(color 0 0 0 0)
	)
	(junction
		(at 194.31 90.17)
		(diameter 0)
		(color 0 0 0 0)
	)
	(junction
		(at 240.03 110.49)
		(diameter 0)
		(color 0 0 0 0)
	)
	(junction
		(at 275.59 115.57)
		(diameter 0)
		(color 0 0 0 0)
	)
	(junction
		(at 257.81 97.79)
		(diameter 0)
		(color 0 0 0 0)
	)
	(junction
		(at 205.74 90.17)
		(diameter 0)
		(color 0 0 0 0)
	)
	(junction
		(at 266.7 97.79)
		(diameter 0)
		(color 0 0 0 0)
	)
	(no_connect
		(at 191.77 85.09)
	)
	(no_connect
		(at 261.62 209.55)
	)
	(bus_entry
		(at 233.68 146.05)
		(size -2.54 -2.54)
		(stroke
			(width 0)
			(type default)
		)
	)
	(bus_entry
		(at 233.68 161.29)
		(size -2.54 -2.54)
		(stroke
			(width 0)
			(type default)
		)
	)
	(bus_entry
		(at 233.68 125.73)
		(size -2.54 -2.54)
		(stroke
			(width 0)
			(type default)
		)
	)
	(bus_entry
		(at 233.68 163.83)
		(size -2.54 -2.54)
		(stroke
			(width 0)
			(type default)
		)
	)
	(bus_entry
		(at 233.68 171.45)
		(size -2.54 -2.54)
		(stroke
			(width 0)
			(type default)
		)
	)
	(bus_entry
		(at 233.68 92.71)
		(size -2.54 2.54)
		(stroke
			(width 0)
			(type default)
		)
	)
	(bus_entry
		(at 233.68 140.97)
		(size -2.54 -2.54)
		(stroke
			(width 0)
			(type default)
		)
	)
	(bus_entry
		(at 233.68 176.53)
		(size -2.54 -2.54)
		(stroke
			(width 0)
			(type default)
		)
	)
	(bus_entry
		(at 233.68 133.35)
		(size -2.54 -2.54)
		(stroke
			(width 0)
			(type default)
		)
	)
	(bus_entry
		(at 233.68 102.87)
		(size -2.54 2.54)
		(stroke
			(width 0)
			(type default)
		)
	)
	(bus_entry
		(at 233.68 168.91)
		(size -2.54 -2.54)
		(stroke
			(width 0)
			(type default)
		)
	)
	(bus_entry
		(at 233.68 130.81)
		(size -2.54 -2.54)
		(stroke
			(width 0)
			(type default)
		)
	)
	(bus_entry
		(at 233.68 123.19)
		(size -2.54 -2.54)
		(stroke
			(width 0)
			(type default)
		)
	)
	(bus_entry
		(at 233.68 138.43)
		(size -2.54 -2.54)
		(stroke
			(width 0)
			(type default)
		)
	)
	(bus_entry
		(at 233.68 148.59)
		(size -2.54 -2.54)
		(stroke
			(width 0)
			(type default)
		)
	)
	(bus_entry
		(at 233.68 153.67)
		(size -2.54 -2.54)
		(stroke
			(width 0)
			(type default)
		)
	)
	(bus_entry
		(at 233.68 100.33)
		(size -2.54 2.54)
		(stroke
			(width 0)
			(type default)
		)
	)
	(bus_entry
		(at 233.68 156.21)
		(size -2.54 -2.54)
		(stroke
			(width 0)
			(type default)
		)
	)
	(bus_entry
		(at 233.68 179.07)
		(size -2.54 -2.54)
		(stroke
			(width 0)
			(type default)
		)
	)
	(bus_entry
		(at 233.68 95.25)
		(size -2.54 2.54)
		(stroke
			(width 0)
			(type default)
		)
	)
	(wire
		(pts
			(xy 287.02 110.49) (xy 292.1 110.49)
		)
		(stroke
			(width 0)
			(type default)
		)
	)
	(wire
		(pts
			(xy 218.44 90.17) (xy 205.74 90.17)
		)
		(stroke
			(width 0)
			(type default)
		)
	)
	(wire
		(pts
			(xy 191.77 90.17) (xy 194.31 90.17)
		)
		(stroke
			(width 0)
			(type default)
		)
	)
	(wire
		(pts
			(xy 275.59 105.41) (xy 275.59 115.57)
		)
		(stroke
			(width 0)
			(type default)
		)
	)
	(wire
		(pts
			(xy 245.11 107.95) (xy 245.11 113.03)
		)
		(stroke
			(width 0)
			(type default)
		)
	)
	(bus
		(pts
			(xy 233.68 148.59) (xy 233.68 153.67)
		)
		(stroke
			(width 0)
			(type default)
		)
	)
	(wire
		(pts
			(xy 223.52 83.82) (xy 223.52 86.36)
		)
		(stroke
			(width 0)
			(type default)
		)
	)
	(wire
		(pts
			(xy 161.29 237.49) (xy 146.05 237.49)
		)
		(stroke
			(width 0)
			(type default)
		)
	)
	(bus
		(pts
			(xy 233.68 179.07) (xy 233.68 181.61)
		)
		(stroke
			(width 0)
			(type default)
		)
	)
	(wire
		(pts
			(xy 212.09 217.17) (xy 196.85 217.17)
		)
		(stroke
			(width 0)
			(type default)
		)
	)
	(bus
		(pts
			(xy 236.22 95.25) (xy 233.68 97.79)
		)
		(stroke
			(width 0)
			(type default)
		)
	)
	(wire
		(pts
			(xy 191.77 95.25) (xy 207.01 95.25)
		)
		(stroke
			(width 0)
			(type default)
		)
	)
	(wire
		(pts
			(xy 240.03 107.95) (xy 240.03 110.49)
		)
		(stroke
			(width 0)
			(type default)
		)
	)
	(wire
		(pts
			(xy 209.55 245.11) (xy 212.09 245.11)
		)
		(stroke
			(width 0)
			(type default)
		)
	)
	(wire
		(pts
			(xy 158.75 219.71) (xy 158.75 222.25)
		)
		(stroke
			(width 0)
			(type default)
		)
	)
	(wire
		(pts
			(xy 191.77 120.65) (xy 231.14 120.65)
		)
		(stroke
			(width 0)
			(type default)
		)
	)
	(wire
		(pts
			(xy 209.55 245.11) (xy 209.55 247.65)
		)
		(stroke
			(width 0)
			(type default)
		)
	)
	(wire
		(pts
			(xy 257.81 110.49) (xy 281.94 110.49)
		)
		(stroke
			(width 0)
			(type default)
		)
	)
	(wire
		(pts
			(xy 246.38 212.09) (xy 261.62 212.09)
		)
		(stroke
			(width 0)
			(type default)
		)
	)
	(wire
		(pts
			(xy 158.75 245.11) (xy 161.29 245.11)
		)
		(stroke
			(width 0)
			(type default)
		)
	)
	(wire
		(pts
			(xy 212.09 237.49) (xy 196.85 237.49)
		)
		(stroke
			(width 0)
			(type default)
		)
	)
	(wire
		(pts
			(xy 191.77 128.27) (xy 231.14 128.27)
		)
		(stroke
			(width 0)
			(type default)
		)
	)
	(wire
		(pts
			(xy 212.09 242.57) (xy 196.85 242.57)
		)
		(stroke
			(width 0)
			(type default)
		)
	)
	(wire
		(pts
			(xy 191.77 146.05) (xy 231.14 146.05)
		)
		(stroke
			(width 0)
			(type default)
		)
	)
	(bus
		(pts
			(xy 233.68 163.83) (xy 233.68 168.91)
		)
		(stroke
			(width 0)
			(type default)
		)
	)
	(wire
		(pts
			(xy 191.77 161.29) (xy 231.14 161.29)
		)
		(stroke
			(width 0)
			(type default)
		)
	)
	(wire
		(pts
			(xy 161.29 209.55) (xy 146.05 209.55)
		)
		(stroke
			(width 0)
			(type default)
		)
	)
	(wire
		(pts
			(xy 191.77 166.37) (xy 231.14 166.37)
		)
		(stroke
			(width 0)
			(type default)
		)
	)
	(wire
		(pts
			(xy 266.7 97.79) (xy 275.59 97.79)
		)
		(stroke
			(width 0)
			(type default)
		)
	)
	(wire
		(pts
			(xy 161.29 234.95) (xy 146.05 234.95)
		)
		(stroke
			(width 0)
			(type default)
		)
	)
	(wire
		(pts
			(xy 212.09 240.03) (xy 196.85 240.03)
		)
		(stroke
			(width 0)
			(type default)
		)
	)
	(wire
		(pts
			(xy 191.77 87.63) (xy 194.31 87.63)
		)
		(stroke
			(width 0)
			(type default)
		)
	)
	(wire
		(pts
			(xy 218.44 76.2) (xy 218.44 78.74)
		)
		(stroke
			(width 0)
			(type default)
		)
	)
	(wire
		(pts
			(xy 245.11 113.03) (xy 266.7 113.03)
		)
		(stroke
			(width 0)
			(type default)
		)
	)
	(wire
		(pts
			(xy 261.62 240.03) (xy 246.38 240.03)
		)
		(stroke
			(width 0)
			(type default)
		)
	)
	(wire
		(pts
			(xy 275.59 115.57) (xy 281.94 115.57)
		)
		(stroke
			(width 0)
			(type default)
		)
	)
	(bus
		(pts
			(xy 233.68 176.53) (xy 233.68 179.07)
		)
		(stroke
			(width 0)
			(type default)
		)
	)
	(wire
		(pts
			(xy 261.62 242.57) (xy 246.38 242.57)
		)
		(stroke
			(width 0)
			(type default)
		)
	)
	(bus
		(pts
			(xy 233.68 156.21) (xy 233.68 161.29)
		)
		(stroke
			(width 0)
			(type default)
		)
	)
	(wire
		(pts
			(xy 194.31 90.17) (xy 194.31 87.63)
		)
		(stroke
			(width 0)
			(type default)
		)
	)
	(wire
		(pts
			(xy 191.77 135.89) (xy 231.14 135.89)
		)
		(stroke
			(width 0)
			(type default)
		)
	)
	(wire
		(pts
			(xy 287.02 115.57) (xy 292.1 115.57)
		)
		(stroke
			(width 0)
			(type default)
		)
	)
	(wire
		(pts
			(xy 212.09 234.95) (xy 196.85 234.95)
		)
		(stroke
			(width 0)
			(type default)
		)
	)
	(wire
		(pts
			(xy 212.09 95.25) (xy 231.14 95.25)
		)
		(stroke
			(width 0)
			(type default)
		)
	)
	(bus
		(pts
			(xy 233.68 140.97) (xy 233.68 138.43)
		)
		(stroke
			(width 0)
			(type default)
		)
	)
	(wire
		(pts
			(xy 250.19 115.57) (xy 275.59 115.57)
		)
		(stroke
			(width 0)
			(type default)
		)
	)
	(wire
		(pts
			(xy 163.83 173.99) (xy 163.83 176.53)
		)
		(stroke
			(width 0)
			(type default)
		)
	)
	(wire
		(pts
			(xy 158.75 245.11) (xy 158.75 247.65)
		)
		(stroke
			(width 0)
			(type default)
		)
	)
	(wire
		(pts
			(xy 191.77 123.19) (xy 231.14 123.19)
		)
		(stroke
			(width 0)
			(type default)
		)
	)
	(bus
		(pts
			(xy 233.68 161.29) (xy 233.68 163.83)
		)
		(stroke
			(width 0)
			(type default)
		)
	)
	(bus
		(pts
			(xy 233.68 168.91) (xy 233.68 171.45)
		)
		(stroke
			(width 0)
			(type default)
		)
	)
	(wire
		(pts
			(xy 205.74 90.17) (xy 205.74 82.55)
		)
		(stroke
			(width 0)
			(type default)
		)
	)
	(wire
		(pts
			(xy 275.59 100.33) (xy 275.59 97.79)
		)
		(stroke
			(width 0)
			(type default)
		)
	)
	(wire
		(pts
			(xy 266.7 100.33) (xy 266.7 97.79)
		)
		(stroke
			(width 0)
			(type default)
		)
	)
	(wire
		(pts
			(xy 261.62 214.63) (xy 246.38 214.63)
		)
		(stroke
			(width 0)
			(type default)
		)
	)
	(wire
		(pts
			(xy 161.29 217.17) (xy 146.05 217.17)
		)
		(stroke
			(width 0)
			(type default)
		)
	)
	(wire
		(pts
			(xy 257.81 95.25) (xy 257.81 97.79)
		)
		(stroke
			(width 0)
			(type default)
		)
	)
	(wire
		(pts
			(xy 287.02 113.03) (xy 292.1 113.03)
		)
		(stroke
			(width 0)
			(type default)
		)
	)
	(bus
		(pts
			(xy 233.68 133.35) (xy 233.68 130.81)
		)
		(stroke
			(width 0)
			(type default)
		)
	)
	(wire
		(pts
			(xy 257.81 105.41) (xy 257.81 110.49)
		)
		(stroke
			(width 0)
			(type default)
		)
	)
	(wire
		(pts
			(xy 191.77 176.53) (xy 231.14 176.53)
		)
		(stroke
			(width 0)
			(type default)
		)
	)
	(wire
		(pts
			(xy 191.77 173.99) (xy 231.14 173.99)
		)
		(stroke
			(width 0)
			(type default)
		)
	)
	(wire
		(pts
			(xy 194.31 82.55) (xy 194.31 87.63)
		)
		(stroke
			(width 0)
			(type default)
		)
	)
	(wire
		(pts
			(xy 191.77 158.75) (xy 231.14 158.75)
		)
		(stroke
			(width 0)
			(type default)
		)
	)
	(bus
		(pts
			(xy 236.22 87.63) (xy 238.76 87.63)
		)
		(stroke
			(width 0)
			(type default)
		)
	)
	(wire
		(pts
			(xy 161.29 214.63) (xy 146.05 214.63)
		)
		(stroke
			(width 0)
			(type default)
		)
	)
	(bus
		(pts
			(xy 233.68 146.05) (xy 233.68 148.59)
		)
		(stroke
			(width 0)
			(type default)
		)
	)
	(wire
		(pts
			(xy 191.77 138.43) (xy 231.14 138.43)
		)
		(stroke
			(width 0)
			(type default)
		)
	)
	(wire
		(pts
			(xy 163.83 176.53) (xy 163.83 179.07)
		)
		(stroke
			(width 0)
			(type default)
		)
	)
	(wire
		(pts
			(xy 261.62 234.95) (xy 246.38 234.95)
		)
		(stroke
			(width 0)
			(type default)
		)
	)
	(wire
		(pts
			(xy 191.77 115.57) (xy 250.19 115.57)
		)
		(stroke
			(width 0)
			(type default)
		)
	)
	(wire
		(pts
			(xy 212.09 209.55) (xy 196.85 209.55)
		)
		(stroke
			(width 0)
			(type default)
		)
	)
	(wire
		(pts
			(xy 191.77 97.79) (xy 207.01 97.79)
		)
		(stroke
			(width 0)
			(type default)
		)
	)
	(bus
		(pts
			(xy 233.68 92.71) (xy 233.68 90.17)
		)
		(stroke
			(width 0)
			(type default)
		)
	)
	(wire
		(pts
			(xy 259.08 245.11) (xy 259.08 247.65)
		)
		(stroke
			(width 0)
			(type default)
		)
	)
	(wire
		(pts
			(xy 205.74 90.17) (xy 194.31 90.17)
		)
		(stroke
			(width 0)
			(type default)
		)
	)
	(wire
		(pts
			(xy 266.7 113.03) (xy 281.94 113.03)
		)
		(stroke
			(width 0)
			(type default)
		)
	)
	(wire
		(pts
			(xy 161.29 240.03) (xy 146.05 240.03)
		)
		(stroke
			(width 0)
			(type default)
		)
	)
	(wire
		(pts
			(xy 259.08 219.71) (xy 261.62 219.71)
		)
		(stroke
			(width 0)
			(type default)
		)
	)
	(wire
		(pts
			(xy 218.44 90.17) (xy 218.44 83.82)
		)
		(stroke
			(width 0)
			(type default)
		)
	)
	(wire
		(pts
			(xy 261.62 237.49) (xy 246.38 237.49)
		)
		(stroke
			(width 0)
			(type default)
		)
	)
	(bus
		(pts
			(xy 233.68 133.35) (xy 233.68 138.43)
		)
		(stroke
			(width 0)
			(type default)
		)
	)
	(wire
		(pts
			(xy 257.81 97.79) (xy 257.81 100.33)
		)
		(stroke
			(width 0)
			(type default)
		)
	)
	(bus
		(pts
			(xy 238.76 184.15) (xy 236.22 184.15)
		)
		(stroke
			(width 0)
			(type default)
		)
	)
	(wire
		(pts
			(xy 259.08 219.71) (xy 259.08 222.25)
		)
		(stroke
			(width 0)
			(type default)
		)
	)
	(wire
		(pts
			(xy 212.09 214.63) (xy 196.85 214.63)
		)
		(stroke
			(width 0)
			(type default)
		)
	)
	(bus
		(pts
			(xy 236.22 184.15) (xy 233.68 181.61)
		)
		(stroke
			(width 0)
			(type default)
		)
	)
	(wire
		(pts
			(xy 191.77 151.13) (xy 231.14 151.13)
		)
		(stroke
			(width 0)
			(type default)
		)
	)
	(wire
		(pts
			(xy 191.77 143.51) (xy 231.14 143.51)
		)
		(stroke
			(width 0)
			(type default)
		)
	)
	(wire
		(pts
			(xy 218.44 76.2) (xy 223.52 76.2)
		)
		(stroke
			(width 0)
			(type default)
		)
	)
	(bus
		(pts
			(xy 233.68 100.33) (xy 233.68 97.79)
		)
		(stroke
			(width 0)
			(type default)
		)
	)
	(wire
		(pts
			(xy 191.77 153.67) (xy 231.14 153.67)
		)
		(stroke
			(width 0)
			(type default)
		)
	)
	(bus
		(pts
			(xy 238.76 95.25) (xy 236.22 95.25)
		)
		(stroke
			(width 0)
			(type default)
		)
	)
	(wire
		(pts
			(xy 209.55 219.71) (xy 212.09 219.71)
		)
		(stroke
			(width 0)
			(type default)
		)
	)
	(wire
		(pts
			(xy 266.7 105.41) (xy 266.7 113.03)
		)
		(stroke
			(width 0)
			(type default)
		)
	)
	(bus
		(pts
			(xy 236.22 87.63) (xy 233.68 90.17)
		)
		(stroke
			(width 0)
			(type default)
		)
	)
	(wire
		(pts
			(xy 166.37 173.99) (xy 163.83 173.99)
		)
		(stroke
			(width 0)
			(type default)
		)
	)
	(bus
		(pts
			(xy 233.68 123.19) (xy 233.68 125.73)
		)
		(stroke
			(width 0)
			(type default)
		)
	)
	(wire
		(pts
			(xy 212.09 97.79) (xy 231.14 97.79)
		)
		(stroke
			(width 0)
			(type default)
		)
	)
	(wire
		(pts
			(xy 240.03 110.49) (xy 257.81 110.49)
		)
		(stroke
			(width 0)
			(type default)
		)
	)
	(wire
		(pts
			(xy 191.77 168.91) (xy 231.14 168.91)
		)
		(stroke
			(width 0)
			(type default)
		)
	)
	(wire
		(pts
			(xy 191.77 110.49) (xy 240.03 110.49)
		)
		(stroke
			(width 0)
			(type default)
		)
	)
	(wire
		(pts
			(xy 209.55 219.71) (xy 209.55 222.25)
		)
		(stroke
			(width 0)
			(type default)
		)
	)
	(wire
		(pts
			(xy 161.29 242.57) (xy 146.05 242.57)
		)
		(stroke
			(width 0)
			(type default)
		)
	)
	(wire
		(pts
			(xy 161.29 212.09) (xy 146.05 212.09)
		)
		(stroke
			(width 0)
			(type default)
		)
	)
	(wire
		(pts
			(xy 191.77 130.81) (xy 231.14 130.81)
		)
		(stroke
			(width 0)
			(type default)
		)
	)
	(wire
		(pts
			(xy 191.77 113.03) (xy 245.11 113.03)
		)
		(stroke
			(width 0)
			(type default)
		)
	)
	(bus
		(pts
			(xy 233.68 153.67) (xy 233.68 156.21)
		)
		(stroke
			(width 0)
			(type default)
		)
	)
	(wire
		(pts
			(xy 250.19 107.95) (xy 250.19 115.57)
		)
		(stroke
			(width 0)
			(type default)
		)
	)
	(wire
		(pts
			(xy 212.09 212.09) (xy 196.85 212.09)
		)
		(stroke
			(width 0)
			(type default)
		)
	)
	(wire
		(pts
			(xy 158.75 219.71) (xy 161.29 219.71)
		)
		(stroke
			(width 0)
			(type default)
		)
	)
	(bus
		(pts
			(xy 233.68 102.87) (xy 233.68 100.33)
		)
		(stroke
			(width 0)
			(type default)
		)
	)
	(bus
		(pts
			(xy 233.68 125.73) (xy 233.68 130.81)
		)
		(stroke
			(width 0)
			(type default)
		)
	)
	(bus
		(pts
			(xy 233.68 140.97) (xy 233.68 146.05)
		)
		(stroke
			(width 0)
			(type default)
		)
	)
	(wire
		(pts
			(xy 257.81 97.79) (xy 266.7 97.79)
		)
		(stroke
			(width 0)
			(type default)
		)
	)
	(bus
		(pts
			(xy 233.68 171.45) (xy 233.68 176.53)
		)
		(stroke
			(width 0)
			(type default)
		)
	)
	(wire
		(pts
			(xy 259.08 245.11) (xy 261.62 245.11)
		)
		(stroke
			(width 0)
			(type default)
		)
	)
	(wire
		(pts
			(xy 261.62 217.17) (xy 246.38 217.17)
		)
		(stroke
			(width 0)
			(type default)
		)
	)
	(bus
		(pts
			(xy 233.68 95.25) (xy 233.68 92.71)
		)
		(stroke
			(width 0)
			(type default)
		)
	)
	(wire
		(pts
			(xy 191.77 102.87) (xy 231.14 102.87)
		)
		(stroke
			(width 0)
			(type default)
		)
	)
	(wire
		(pts
			(xy 191.77 105.41) (xy 231.14 105.41)
		)
		(stroke
			(width 0)
			(type default)
		)
	)
	(wire
		(pts
			(xy 163.83 176.53) (xy 166.37 176.53)
		)
		(stroke
			(width 0)
			(type default)
		)
	)
	(wire
		(pts
			(xy 223.52 76.2) (xy 223.52 78.74)
		)
		(stroke
			(width 0)
			(type default)
		)
	)
	(label "SCL"
		(at 246.38 234.95 0)
		(effects
			(font
				(size 1.27 1.27)
			)
			(justify left bottom)
		)
	)
	(label "~{PE_ RST}_R"
		(at 218.44 110.49 0)
		(effects
			(font
				(size 1.27 1.27)
			)
			(justify left bottom)
		)
	)
	(label "PCIe_{x4}.TX0+"
		(at 218.44 120.65 0)
		(effects
			(font
				(size 1.27 1.27)
			)
			(justify left bottom)
		)
	)
	(label "REFCLK.-"
		(at 246.38 217.17 0)
		(effects
			(font
				(size 1.27 1.27)
			)
			(justify left bottom)
		)
	)
	(label "~{PE_ RST}_R"
		(at 246.38 240.03 0)
		(effects
			(font
				(size 1.27 1.27)
			)
			(justify left bottom)
		)
	)
	(label "PCIe_{x4}.RX1+"
		(at 218.44 158.75 0)
		(effects
			(font
				(size 1.27 1.27)
			)
			(justify left bottom)
		)
	)
	(label "PCIe_{x4}.TX1+"
		(at 218.44 128.27 0)
		(effects
			(font
				(size 1.27 1.27)
			)
			(justify left bottom)
		)
	)
	(label "SMBus.SDA"
		(at 218.44 97.79 0)
		(effects
			(font
				(size 1.27 1.27)
			)
			(justify left bottom)
		)
	)
	(label "PCIe_{x4}.TX1-"
		(at 218.44 130.81 0)
		(effects
			(font
				(size 1.27 1.27)
			)
			(justify left bottom)
		)
	)
	(label "SCL"
		(at 193.04 95.25 0)
		(effects
			(font
				(size 1.27 1.27)
			)
			(justify left bottom)
		)
	)
	(label "~{CPRSNT}_R"
		(at 218.44 113.03 0)
		(effects
			(font
				(size 1.27 1.27)
			)
			(justify left bottom)
		)
	)
	(label "PCIe_{x4}.TX1-"
		(at 196.85 217.17 0)
		(effects
			(font
				(size 1.27 1.27)
			)
			(justify left bottom)
		)
	)
	(label "~{CWAKE}_R"
		(at 246.38 212.09 0)
		(effects
			(font
				(size 1.27 1.27)
			)
			(justify left bottom)
		)
	)
	(label "SMBus.SCL"
		(at 218.44 95.25 0)
		(effects
			(font
				(size 1.27 1.27)
			)
			(justify left bottom)
		)
	)
	(label "PCIe_{x4}.TX0-"
		(at 218.44 123.19 0)
		(effects
			(font
				(size 1.27 1.27)
			)
			(justify left bottom)
		)
	)
	(label "PCIe_{x4}.RX1-"
		(at 146.05 217.17 0)
		(effects
			(font
				(size 1.27 1.27)
			)
			(justify left bottom)
		)
	)
	(label "PCIe_{x4}.TX0+"
		(at 196.85 209.55 0)
		(effects
			(font
				(size 1.27 1.27)
			)
			(justify left bottom)
		)
	)
	(label "~{CPRSNT}_R"
		(at 246.38 242.57 0)
		(effects
			(font
				(size 1.27 1.27)
			)
			(justify left bottom)
		)
	)
	(label "REFCLK.+"
		(at 246.38 214.63 0)
		(effects
			(font
				(size 1.27 1.27)
			)
			(justify left bottom)
		)
	)
	(label "PCIe_{x4}.TX2+"
		(at 196.85 234.95 0)
		(effects
			(font
				(size 1.27 1.27)
			)
			(justify left bottom)
		)
	)
	(label "PCIe_{x4}.TX3+"
		(at 196.85 240.03 0)
		(effects
			(font
				(size 1.27 1.27)
			)
			(justify left bottom)
		)
	)
	(label "PCIe_{x4}.RX3+"
		(at 218.44 173.99 0)
		(effects
			(font
				(size 1.27 1.27)
			)
			(justify left bottom)
		)
	)
	(label "PCIe_{x4}.RX2-"
		(at 218.44 168.91 0)
		(effects
			(font
				(size 1.27 1.27)
			)
			(justify left bottom)
		)
	)
	(label "PCIe_{x4}.TX3+"
		(at 218.44 143.51 0)
		(effects
			(font
				(size 1.27 1.27)
			)
			(justify left bottom)
		)
	)
	(label "PCIe_{x4}.TX2-"
		(at 218.44 138.43 0)
		(effects
			(font
				(size 1.27 1.27)
			)
			(justify left bottom)
		)
	)
	(label "PCIe_{x4}.TX0-"
		(at 196.85 212.09 0)
		(effects
			(font
				(size 1.27 1.27)
			)
			(justify left bottom)
		)
	)
	(label "PCIe_{x4}.TX3-"
		(at 196.85 242.57 0)
		(effects
			(font
				(size 1.27 1.27)
			)
			(justify left bottom)
		)
	)
	(label "SDA"
		(at 246.38 237.49 0)
		(effects
			(font
				(size 1.27 1.27)
			)
			(justify left bottom)
		)
	)
	(label "REFCLK.-"
		(at 218.44 105.41 0)
		(effects
			(font
				(size 1.27 1.27)
			)
			(justify left bottom)
		)
	)
	(label "PCIe_{x4}.TX3-"
		(at 218.44 146.05 0)
		(effects
			(font
				(size 1.27 1.27)
			)
			(justify left bottom)
		)
	)
	(label "PCIe_{x4}.RX3+"
		(at 146.05 240.03 0)
		(effects
			(font
				(size 1.27 1.27)
			)
			(justify left bottom)
		)
	)
	(label "PCIe_{x4}.RX0-"
		(at 218.44 153.67 0)
		(effects
			(font
				(size 1.27 1.27)
			)
			(justify left bottom)
		)
	)
	(label "PCIe_{x4}.TX1+"
		(at 196.85 214.63 0)
		(effects
			(font
				(size 1.27 1.27)
			)
			(justify left bottom)
		)
	)
	(label "PCIe_{x4}.TX2-"
		(at 196.85 237.49 0)
		(effects
			(font
				(size 1.27 1.27)
			)
			(justify left bottom)
		)
	)
	(label "SDA"
		(at 193.04 97.79 0)
		(effects
			(font
				(size 1.27 1.27)
			)
			(justify left bottom)
		)
	)
	(label "PCIe_{x4}.TX2+"
		(at 218.44 135.89 0)
		(effects
			(font
				(size 1.27 1.27)
			)
			(justify left bottom)
		)
	)
	(label "PCIe_{x4}.RX2+"
		(at 146.05 234.95 0)
		(effects
			(font
				(size 1.27 1.27)
			)
			(justify left bottom)
		)
	)
	(label "PCIe_{x4}.RX3-"
		(at 146.05 242.57 0)
		(effects
			(font
				(size 1.27 1.27)
			)
			(justify left bottom)
		)
	)
	(label "PCIe_{x4}.RX1+"
		(at 146.05 214.63 0)
		(effects
			(font
				(size 1.27 1.27)
			)
			(justify left bottom)
		)
	)
	(label "REFCLK.+"
		(at 218.44 102.87 0)
		(effects
			(font
				(size 1.27 1.27)
			)
			(justify left bottom)
		)
	)
	(label "PCIe_{x4}.RX2-"
		(at 146.05 237.49 0)
		(effects
			(font
				(size 1.27 1.27)
			)
			(justify left bottom)
		)
	)
	(label "PCIe_{x4}.RX0-"
		(at 146.05 212.09 0)
		(effects
			(font
				(size 1.27 1.27)
			)
			(justify left bottom)
		)
	)
	(label "PCIe_{x4}.RX0+"
		(at 218.44 151.13 0)
		(effects
			(font
				(size 1.27 1.27)
			)
			(justify left bottom)
		)
	)
	(label "PCIe_{x4}.RX1-"
		(at 218.44 161.29 0)
		(effects
			(font
				(size 1.27 1.27)
			)
			(justify left bottom)
		)
	)
	(label "PCIe_{x4}.RX0+"
		(at 146.05 209.55 0)
		(effects
			(font
				(size 1.27 1.27)
			)
			(justify left bottom)
		)
	)
	(label "~{CWAKE}_R"
		(at 218.44 115.57 0)
		(effects
			(font
				(size 1.27 1.27)
			)
			(justify left bottom)
		)
	)
	(label "PCIe_{x4}.RX3-"
		(at 218.44 176.53 0)
		(effects
			(font
				(size 1.27 1.27)
			)
			(justify left bottom)
		)
	)
	(label "PCIe_{x4}.RX2+"
		(at 218.44 166.37 0)
		(effects
			(font
				(size 1.27 1.27)
			)
			(justify left bottom)
		)
	)
	(hierarchical_label "~{PE_WAKE}"
		(shape input)
		(at 292.1 115.57 0)
		(effects
			(font
				(size 1.27 1.27)
			)
			(justify left)
		)
	)
	(hierarchical_label "~{CPRSNT}"
		(shape input)
		(at 292.1 113.03 0)
		(effects
			(font
				(size 1.27 1.27)
			)
			(justify left)
		)
	)
	(hierarchical_label "PCIe_{x4}{PCIe}"
		(shape bidirectional)
		(at 238.76 184.15 0)
		(effects
			(font
				(size 1.27 1.27)
			)
			(justify left)
		)
	)
	(hierarchical_label "REFCLK{CLK}"
		(shape output)
		(at 238.76 95.25 0)
		(effects
			(font
				(size 1.27 1.27)
			)
			(justify left)
		)
	)
	(hierarchical_label "~{PE_RST}"
		(shape output)
		(at 292.1 110.49 0)
		(effects
			(font
				(size 1.27 1.27)
			)
			(justify left)
		)
	)
	(hierarchical_label "SMBus{I2C}"
		(shape bidirectional)
		(at 238.76 87.63 0)
		(effects
			(font
				(size 1.27 1.27)
			)
			(justify left)
		)
	)
	(symbol
		(lib_id "antmicroResistors0402:R_10k_0402")
		(at 275.59 105.41 90)
		(unit 1)
		(exclude_from_sim no)
		(in_bom no)
		(on_board yes)
		(dnp yes)
		(property "Reference" "R166"
			(at 276.86 101.6 90)
			(effects
				(font
					(size 1.27 1.27)
					(thickness 0.15)
				)
				(justify right)
			)
		)
		(property "Value" "R_10k_0402"
			(at 288.29 85.09 0)
			(effects
				(font
					(size 1.27 1.27)
					(thickness 0.15)
				)
				(justify left bottom)
				(hide yes)
			)
		)
		(property "Footprint" "antmicro-footprints:R_0402_1005Metric"
			(at 290.83 85.09 0)
			(effects
				(font
					(size 1.27 1.27)
					(thickness 0.15)
				)
				(justify left bottom)
				(hide yes)
			)
		)
		(property "Datasheet" "https://www.bourns.com/docs/product-datasheets/cr.pdf"
			(at 293.37 85.09 0)
			(effects
				(font
					(size 1.27 1.27)
					(thickness 0.15)
				)
				(justify left bottom)
				(hide yes)
			)
		)
		(property "Description" "SMD Chip Resistor, 10 kohm, ± 1%, 62.5 mW, 0402 [1005 Metric], Thick Film, General Purpose"
			(at 306.07 85.09 0)
			(effects
				(font
					(size 1.27 1.27)
				)
				(justify left bottom)
				(hide yes)
			)
		)
		(property "MPN" "CR0402-FX-1002GLF"
			(at 295.91 85.09 0)
			(effects
				(font
					(size 1.27 1.27)
					(thickness 0.15)
				)
				(justify left bottom)
				(hide yes)
			)
		)
		(property "Manufacturer" "Bourns"
			(at 298.45 85.09 0)
			(effects
				(font
					(size 1.27 1.27)
					(thickness 0.15)
				)
				(justify left bottom)
				(hide yes)
			)
		)
		(property "License" "Apache-2.0"
			(at 300.99 85.09 0)
			(effects
				(font
					(size 1.27 1.27)
					(thickness 0.15)
				)
				(justify left bottom)
				(hide yes)
			)
		)
		(property "Author" "Antmicro"
			(at 303.53 85.09 0)
			(effects
				(font
					(size 1.27 1.27)
					(thickness 0.15)
				)
				(justify left bottom)
				(hide yes)
			)
		)
		(property "Val" "10k"
			(at 276.86 104.14 90)
			(effects
				(font
					(size 1.27 1.27)
					(thickness 0.15)
				)
				(justify right)
			)
		)
		(property "Tolerance" "1%"
			(at 285.75 85.09 0)
			(effects
				(font
					(size 1.27 1.27)
				)
				(justify left bottom)
				(hide yes)
			)
		)
		(pin "2"
		)
		(pin "1"
		)
		(instances
			(project "OCuLink to 10GbE adapter"
				(path ""
					(reference "R166")
					(unit 1)
				)
			)
		)
	)
	(symbol
		(lib_id "antmicroTVSDiodes:ESD204DQAR")
		(at 212.09 234.95 0)
		(unit 1)
		(exclude_from_sim no)
		(in_bom yes)
		(on_board yes)
		(dnp no)
		(fields_autoplaced yes)
		(property "Reference" "D8"
			(at 222.25 238.76 0)
			(effects
				(font
					(size 1.27 1.27)
					(thickness 0.15)
				)
				(justify left)
			)
		)
		(property "Value" "ESD204DQAR"
			(at 236.22 240.03 0)
			(effects
				(font
					(size 1.27 1.27)
					(thickness 0.15)
				)
				(justify left bottom)
				(hide yes)
			)
		)
		(property "Footprint" "antmicro-footprints:USON-10_2.5x1mm_P0.5mm"
			(at 236.22 242.57 0)
			(effects
				(font
					(size 1.27 1.27)
					(thickness 0.15)
				)
				(justify left bottom)
				(hide yes)
			)
		)
		(property "Datasheet" "https://www.ti.com/lit/ds/symlink/esd204.pdf?ts=1706004844383&ref_url=https%253A%252F%252Fwww.ti.com%252Finterface%252Fdiodes%252Fesd-protection-diodes%252Fproducts.html"
			(at 236.22 245.11 0)
			(effects
				(font
					(size 1.27 1.27)
					(thickness 0.15)
				)
				(justify left bottom)
				(hide yes)
			)
		)
		(property "Description" "TVS diode array, 30 kV, USON-10, 3.6 V, 0.55 pF"
			(at 236.22 255.27 0)
			(effects
				(font
					(size 1.27 1.27)
				)
				(justify left bottom)
				(hide yes)
			)
		)
		(property "MPN" "ESD204DQAR"
			(at 222.25 241.3 0)
			(effects
				(font
					(size 1.27 1.27)
					(thickness 0.15)
				)
				(justify left)
			)
		)
		(property "Manufacturer" "Texas Instruments"
			(at 236.22 247.65 0)
			(effects
				(font
					(size 1.27 1.27)
					(thickness 0.15)
				)
				(justify left bottom)
				(hide yes)
			)
		)
		(property "Author" "Antmicro"
			(at 236.22 250.19 0)
			(effects
				(font
					(size 1.27 1.27)
					(thickness 0.15)
				)
				(justify left bottom)
				(hide yes)
			)
		)
		(property "License" "Apache-2.0"
			(at 236.22 252.73 0)
			(effects
				(font
					(size 1.27 1.27)
					(thickness 0.15)
				)
				(justify left bottom)
				(hide yes)
			)
		)
		(pin "3"
		)
		(pin "10"
		)
		(pin "1"
		)
		(pin "4"
		)
		(pin "9"
		)
		(pin "5"
		)
		(pin "7"
		)
		(pin "6"
		)
		(pin "8"
		)
		(pin "2"
		)
		(instances
			(project "OCuLink to 10GbE adapter"
				(path ""
					(reference "D8")
					(unit 1)
				)
			)
		)
	)
	(symbol
		(lib_id "antmicroResistors0402:R_0R_0402")
		(at 281.94 115.57 0)
		(unit 1)
		(exclude_from_sim no)
		(in_bom yes)
		(on_board yes)
		(dnp no)
		(property "Reference" "R169"
			(at 281.94 114.3 0)
			(effects
				(font
					(size 1.27 1.27)
					(thickness 0.15)
				)
				(justify right)
			)
		)
		(property "Value" "R_0R_0402"
			(at 302.26 128.27 0)
			(effects
				(font
					(size 1.27 1.27)
					(thickness 0.15)
				)
				(justify left bottom)
				(hide yes)
			)
		)
		(property "Footprint" "antmicro-footprints:R_0402_1005Metric"
			(at 302.26 130.81 0)
			(effects
				(font
					(size 1.27 1.27)
					(thickness 0.15)
				)
				(justify left bottom)
				(hide yes)
			)
		)
		(property "Datasheet" "https://industrial.panasonic.com/cdbs/www-data/pdf/RDA0000/AOA0000C301.pdf"
			(at 302.26 133.35 0)
			(effects
				(font
					(size 1.27 1.27)
					(thickness 0.15)
				)
				(justify left bottom)
				(hide yes)
			)
		)
		(property "Description" "SMD Chip Resistor, Jumper, 0 ohm, 100 mW, 0402 [1005 Metric], Thick Film, General Purpose"
			(at 281.94 115.57 0)
			(effects
				(font
					(size 1.27 1.27)
				)
				(hide yes)
			)
		)
		(property "MPN" "ERJ2GE0R00X"
			(at 302.26 135.89 0)
			(effects
				(font
					(size 1.27 1.27)
					(thickness 0.15)
				)
				(justify left bottom)
				(hide yes)
			)
		)
		(property "Manufacturer" "Panasonic"
			(at 302.26 138.43 0)
			(effects
				(font
					(size 1.27 1.27)
					(thickness 0.15)
				)
				(justify left bottom)
				(hide yes)
			)
		)
		(property "License" "Apache-2.0"
			(at 302.26 140.97 0)
			(effects
				(font
					(size 1.27 1.27)
					(thickness 0.15)
				)
				(justify left bottom)
				(hide yes)
			)
		)
		(property "Author" "Antmicro"
			(at 302.26 143.51 0)
			(effects
				(font
					(size 1.27 1.27)
					(thickness 0.15)
				)
				(justify left bottom)
				(hide yes)
			)
		)
		(property "Val" "0R"
			(at 287.02 114.3 0)
			(effects
				(font
					(size 1.27 1.27)
					(thickness 0.15)
				)
				(justify left)
			)
		)
		(property "Tolerance" "~"
			(at 302.26 125.73 0)
			(effects
				(font
					(size 1.27 1.27)
				)
				(justify left bottom)
				(hide yes)
			)
		)
		(property "Current" "1A"
			(at 302.26 146.05 0)
			(effects
				(font
					(size 1.27 1.27)
					(thickness 0.15)
				)
				(justify left bottom)
				(hide yes)
			)
		)
		(pin "2"
		)
		(pin "1"
		)
		(instances
			(project ""
				(path ""
					(reference "R169")
					(unit 1)
				)
			)
		)
	)
	(symbol
		(lib_id "antmicropower:PWR_FLAG")
		(at 205.74 82.55 0)
		(unit 1)
		(exclude_from_sim no)
		(in_bom yes)
		(on_board yes)
		(dnp no)
		(property "Reference" "#FLG021"
			(at 205.74 80.645 0)
			(effects
				(font
					(size 1.27 1.27)
				)
				(hide yes)
			)
		)
		(property "Value" "PWR_FLAG"
			(at 205.74 78.74 0)
			(effects
				(font
					(size 1.27 1.27)
				)
			)
		)
		(property "Footprint" ""
			(at 205.74 82.55 0)
			(effects
				(font
					(size 1.27 1.27)
				)
				(hide yes)
			)
		)
		(property "Datasheet" ""
			(at 205.74 82.55 0)
			(effects
				(font
					(size 1.27 1.27)
				)
				(hide yes)
			)
		)
		(property "Description" ""
			(at 205.74 85.09 0)
			(effects
				(font
					(size 1.27 1.27)
				)
				(justify left bottom)
				(hide yes)
			)
		)
		(pin "1"
		)
		(instances
			(project ""
				(path ""
					(reference "#FLG021")
					(unit 1)
				)
			)
		)
	)
	(symbol
		(lib_id "antmicroResistors0402:R_0R_0402")
		(at 207.01 95.25 0)
		(unit 1)
		(exclude_from_sim no)
		(in_bom yes)
		(on_board yes)
		(dnp no)
		(property "Reference" "R162"
			(at 207.01 93.98 0)
			(effects
				(font
					(size 1.27 1.27)
					(thickness 0.15)
				)
				(justify right)
			)
		)
		(property "Value" "R_0R_0402"
			(at 227.33 107.95 0)
			(effects
				(font
					(size 1.27 1.27)
					(thickness 0.15)
				)
				(justify left bottom)
				(hide yes)
			)
		)
		(property "Footprint" "antmicro-footprints:R_0402_1005Metric"
			(at 227.33 110.49 0)
			(effects
				(font
					(size 1.27 1.27)
					(thickness 0.15)
				)
				(justify left bottom)
				(hide yes)
			)
		)
		(property "Datasheet" "https://industrial.panasonic.com/cdbs/www-data/pdf/RDA0000/AOA0000C301.pdf"
			(at 227.33 113.03 0)
			(effects
				(font
					(size 1.27 1.27)
					(thickness 0.15)
				)
				(justify left bottom)
				(hide yes)
			)
		)
		(property "Description" "SMD Chip Resistor, Jumper, 0 ohm, 100 mW, 0402 [1005 Metric], Thick Film, General Purpose"
			(at 207.01 95.25 0)
			(effects
				(font
					(size 1.27 1.27)
				)
				(hide yes)
			)
		)
		(property "MPN" "ERJ2GE0R00X"
			(at 227.33 115.57 0)
			(effects
				(font
					(size 1.27 1.27)
					(thickness 0.15)
				)
				(justify left bottom)
				(hide yes)
			)
		)
		(property "Manufacturer" "Panasonic"
			(at 227.33 118.11 0)
			(effects
				(font
					(size 1.27 1.27)
					(thickness 0.15)
				)
				(justify left bottom)
				(hide yes)
			)
		)
		(property "License" "Apache-2.0"
			(at 227.33 120.65 0)
			(effects
				(font
					(size 1.27 1.27)
					(thickness 0.15)
				)
				(justify left bottom)
				(hide yes)
			)
		)
		(property "Author" "Antmicro"
			(at 227.33 123.19 0)
			(effects
				(font
					(size 1.27 1.27)
					(thickness 0.15)
				)
				(justify left bottom)
				(hide yes)
			)
		)
		(property "Val" "0R"
			(at 212.09 93.98 0)
			(effects
				(font
					(size 1.27 1.27)
					(thickness 0.15)
				)
				(justify left)
			)
		)
		(property "Tolerance" "~"
			(at 227.33 105.41 0)
			(effects
				(font
					(size 1.27 1.27)
				)
				(justify left bottom)
				(hide yes)
			)
		)
		(property "Current" "1A"
			(at 227.33 125.73 0)
			(effects
				(font
					(size 1.27 1.27)
					(thickness 0.15)
				)
				(justify left bottom)
				(hide yes)
			)
		)
		(pin "2"
		)
		(pin "1"
		)
		(instances
			(project "OCuLink to 10GbE adapter"
				(path ""
					(reference "R162")
					(unit 1)
				)
			)
		)
	)
	(symbol
		(lib_id "antmicroTVSDiodes:ESD204DQAR")
		(at 261.62 234.95 0)
		(unit 1)
		(exclude_from_sim no)
		(in_bom yes)
		(on_board yes)
		(dnp no)
		(fields_autoplaced yes)
		(property "Reference" "D9"
			(at 271.78 238.76 0)
			(effects
				(font
					(size 1.27 1.27)
					(thickness 0.15)
				)
				(justify left)
			)
		)
		(property "Value" "ESD204DQAR"
			(at 285.75 240.03 0)
			(effects
				(font
					(size 1.27 1.27)
					(thickness 0.15)
				)
				(justify left bottom)
				(hide yes)
			)
		)
		(property "Footprint" "antmicro-footprints:USON-10_2.5x1mm_P0.5mm"
			(at 285.75 242.57 0)
			(effects
				(font
					(size 1.27 1.27)
					(thickness 0.15)
				)
				(justify left bottom)
				(hide yes)
			)
		)
		(property "Datasheet" "https://www.ti.com/lit/ds/symlink/esd204.pdf?ts=1706004844383&ref_url=https%253A%252F%252Fwww.ti.com%252Finterface%252Fdiodes%252Fesd-protection-diodes%252Fproducts.html"
			(at 285.75 245.11 0)
			(effects
				(font
					(size 1.27 1.27)
					(thickness 0.15)
				)
				(justify left bottom)
				(hide yes)
			)
		)
		(property "Description" "TVS diode array, 30 kV, USON-10, 3.6 V, 0.55 pF"
			(at 285.75 255.27 0)
			(effects
				(font
					(size 1.27 1.27)
				)
				(justify left bottom)
				(hide yes)
			)
		)
		(property "MPN" "ESD204DQAR"
			(at 271.78 241.3 0)
			(effects
				(font
					(size 1.27 1.27)
					(thickness 0.15)
				)
				(justify left)
			)
		)
		(property "Manufacturer" "Texas Instruments"
			(at 285.75 247.65 0)
			(effects
				(font
					(size 1.27 1.27)
					(thickness 0.15)
				)
				(justify left bottom)
				(hide yes)
			)
		)
		(property "Author" "Antmicro"
			(at 285.75 250.19 0)
			(effects
				(font
					(size 1.27 1.27)
					(thickness 0.15)
				)
				(justify left bottom)
				(hide yes)
			)
		)
		(property "License" "Apache-2.0"
			(at 285.75 252.73 0)
			(effects
				(font
					(size 1.27 1.27)
					(thickness 0.15)
				)
				(justify left bottom)
				(hide yes)
			)
		)
		(pin "3"
		)
		(pin "10"
		)
		(pin "1"
		)
		(pin "4"
		)
		(pin "9"
		)
		(pin "5"
		)
		(pin "7"
		)
		(pin "6"
		)
		(pin "8"
		)
		(pin "2"
		)
		(instances
			(project "OCuLink to 10GbE adapter"
				(path ""
					(reference "D9")
					(unit 1)
				)
			)
		)
	)
	(symbol
		(lib_id "antmicroResistors0402:R_10k_0402")
		(at 257.81 105.41 90)
		(unit 1)
		(exclude_from_sim no)
		(in_bom no)
		(on_board yes)
		(dnp yes)
		(property "Reference" "R164"
			(at 259.08 101.6 90)
			(effects
				(font
					(size 1.27 1.27)
					(thickness 0.15)
				)
				(justify right)
			)
		)
		(property "Value" "R_10k_0402"
			(at 270.51 85.09 0)
			(effects
				(font
					(size 1.27 1.27)
					(thickness 0.15)
				)
				(justify left bottom)
				(hide yes)
			)
		)
		(property "Footprint" "antmicro-footprints:R_0402_1005Metric"
			(at 273.05 85.09 0)
			(effects
				(font
					(size 1.27 1.27)
					(thickness 0.15)
				)
				(justify left bottom)
				(hide yes)
			)
		)
		(property "Datasheet" "https://www.bourns.com/docs/product-datasheets/cr.pdf"
			(at 275.59 85.09 0)
			(effects
				(font
					(size 1.27 1.27)
					(thickness 0.15)
				)
				(justify left bottom)
				(hide yes)
			)
		)
		(property "Description" "SMD Chip Resistor, 10 kohm, ± 1%, 62.5 mW, 0402 [1005 Metric], Thick Film, General Purpose"
			(at 288.29 85.09 0)
			(effects
				(font
					(size 1.27 1.27)
				)
				(justify left bottom)
				(hide yes)
			)
		)
		(property "MPN" "CR0402-FX-1002GLF"
			(at 278.13 85.09 0)
			(effects
				(font
					(size 1.27 1.27)
					(thickness 0.15)
				)
				(justify left bottom)
				(hide yes)
			)
		)
		(property "Manufacturer" "Bourns"
			(at 280.67 85.09 0)
			(effects
				(font
					(size 1.27 1.27)
					(thickness 0.15)
				)
				(justify left bottom)
				(hide yes)
			)
		)
		(property "License" "Apache-2.0"
			(at 283.21 85.09 0)
			(effects
				(font
					(size 1.27 1.27)
					(thickness 0.15)
				)
				(justify left bottom)
				(hide yes)
			)
		)
		(property "Author" "Antmicro"
			(at 285.75 85.09 0)
			(effects
				(font
					(size 1.27 1.27)
					(thickness 0.15)
				)
				(justify left bottom)
				(hide yes)
			)
		)
		(property "Val" "10k"
			(at 259.08 104.14 90)
			(effects
				(font
					(size 1.27 1.27)
					(thickness 0.15)
				)
				(justify right)
			)
		)
		(property "Tolerance" "1%"
			(at 267.97 85.09 0)
			(effects
				(font
					(size 1.27 1.27)
				)
				(justify left bottom)
				(hide yes)
			)
		)
		(pin "2"
		)
		(pin "1"
		)
		(instances
			(project ""
				(path ""
					(reference "R164")
					(unit 1)
				)
			)
		)
	)
	(symbol
		(lib_id "antmicropower:GND")
		(at 158.75 222.25 0)
		(unit 1)
		(exclude_from_sim no)
		(in_bom yes)
		(on_board yes)
		(dnp no)
		(property "Reference" "#PWR0322"
			(at 167.64 224.79 0)
			(effects
				(font
					(size 1.27 1.27)
					(thickness 0.15)
				)
				(justify left bottom)
				(hide yes)
			)
		)
		(property "Value" "GND"
			(at 158.75 226.06 0)
			(effects
				(font
					(size 1.27 1.27)
					(thickness 0.15)
				)
			)
		)
		(property "Footprint" ""
			(at 167.64 229.87 0)
			(effects
				(font
					(size 1.27 1.27)
					(thickness 0.15)
				)
				(justify left bottom)
				(hide yes)
			)
		)
		(property "Datasheet" ""
			(at 167.64 234.95 0)
			(effects
				(font
					(size 1.27 1.27)
					(thickness 0.15)
				)
				(justify left bottom)
				(hide yes)
			)
		)
		(property "Description" ""
			(at 158.75 222.25 0)
			(effects
				(font
					(size 1.27 1.27)
				)
				(hide yes)
			)
		)
		(property "Author" "Antmicro"
			(at 167.64 229.87 0)
			(effects
				(font
					(size 1.27 1.27)
					(thickness 0.15)
				)
				(justify left bottom)
				(hide yes)
			)
		)
		(property "License" "Apache-2.0"
			(at 167.64 232.41 0)
			(effects
				(font
					(size 1.27 1.27)
					(thickness 0.15)
				)
				(justify left bottom)
				(hide yes)
			)
		)
		(pin "1"
		)
		(instances
			(project "OCuLink to 10GbE adapter"
				(path ""
					(reference "#PWR0322")
					(unit 1)
				)
			)
		)
	)
	(symbol
		(lib_id "antmicroResistors0402:R_1k_0402")
		(at 218.44 78.74 270)
		(unit 1)
		(exclude_from_sim no)
		(in_bom yes)
		(on_board yes)
		(dnp no)
		(property "Reference" "R127"
			(at 217.17 80.01 90)
			(effects
				(font
					(size 1.27 1.27)
					(thickness 0.15)
				)
				(justify right)
			)
		)
		(property "Value" "R_1k_0402"
			(at 205.74 99.06 0)
			(effects
				(font
					(size 1.27 1.27)
					(thickness 0.15)
				)
				(justify left bottom)
				(hide yes)
			)
		)
		(property "Footprint" "antmicro-footprints:R_0402_1005Metric"
			(at 203.2 99.06 0)
			(effects
				(font
					(size 1.27 1.27)
					(thickness 0.15)
				)
				(justify left bottom)
				(hide yes)
			)
		)
		(property "Datasheet" "https://www.bourns.com/docs/product-datasheets/cr.pdf"
			(at 200.66 99.06 0)
			(effects
				(font
					(size 1.27 1.27)
					(thickness 0.15)
				)
				(justify left bottom)
				(hide yes)
			)
		)
		(property "Description" "SMD Chip Resistor, 1 kohm, ± 1%, 63 mW, 0402 [1005 Metric], Thick Film, General Purpose"
			(at 187.96 99.06 0)
			(effects
				(font
					(size 1.27 1.27)
				)
				(justify left bottom)
				(hide yes)
			)
		)
		(property "MPN" "CR0402-FX-1001GLF"
			(at 198.12 99.06 0)
			(effects
				(font
					(size 1.27 1.27)
					(thickness 0.15)
				)
				(justify left bottom)
				(hide yes)
			)
		)
		(property "Manufacturer" "Bourns"
			(at 195.58 99.06 0)
			(effects
				(font
					(size 1.27 1.27)
					(thickness 0.15)
				)
				(justify left bottom)
				(hide yes)
			)
		)
		(property "License" "Apache-2.0"
			(at 193.04 99.06 0)
			(effects
				(font
					(size 1.27 1.27)
					(thickness 0.15)
				)
				(justify left bottom)
				(hide yes)
			)
		)
		(property "Author" "Antmicro"
			(at 190.5 99.06 0)
			(effects
				(font
					(size 1.27 1.27)
					(thickness 0.15)
				)
				(justify left bottom)
				(hide yes)
			)
		)
		(property "Val" "1k"
			(at 217.17 82.55 90)
			(effects
				(font
					(size 1.27 1.27)
					(thickness 0.15)
				)
				(justify right)
			)
		)
		(property "Tolerance" "1%"
			(at 208.28 99.06 0)
			(effects
				(font
					(size 1.27 1.27)
				)
				(justify left bottom)
				(hide yes)
			)
		)
		(pin "1"
		)
		(pin "2"
		)
		(instances
			(project "oculink-to-10gbe-adapter"
				(path ""
					(reference "R127")
					(unit 1)
				)
			)
		)
	)
	(symbol
		(lib_id "antmicroTVSDiodes:ESD204DQAR")
		(at 161.29 209.55 0)
		(unit 1)
		(exclude_from_sim no)
		(in_bom yes)
		(on_board yes)
		(dnp no)
		(fields_autoplaced yes)
		(property "Reference" "D4"
			(at 171.45 213.36 0)
			(effects
				(font
					(size 1.27 1.27)
					(thickness 0.15)
				)
				(justify left)
			)
		)
		(property "Value" "ESD204DQAR"
			(at 185.42 214.63 0)
			(effects
				(font
					(size 1.27 1.27)
					(thickness 0.15)
				)
				(justify left bottom)
				(hide yes)
			)
		)
		(property "Footprint" "antmicro-footprints:USON-10_2.5x1mm_P0.5mm"
			(at 185.42 217.17 0)
			(effects
				(font
					(size 1.27 1.27)
					(thickness 0.15)
				)
				(justify left bottom)
				(hide yes)
			)
		)
		(property "Datasheet" "https://www.ti.com/lit/ds/symlink/esd204.pdf?ts=1706004844383&ref_url=https%253A%252F%252Fwww.ti.com%252Finterface%252Fdiodes%252Fesd-protection-diodes%252Fproducts.html"
			(at 185.42 219.71 0)
			(effects
				(font
					(size 1.27 1.27)
					(thickness 0.15)
				)
				(justify left bottom)
				(hide yes)
			)
		)
		(property "Description" "TVS diode array, 30 kV, USON-10, 3.6 V, 0.55 pF"
			(at 185.42 229.87 0)
			(effects
				(font
					(size 1.27 1.27)
				)
				(justify left bottom)
				(hide yes)
			)
		)
		(property "MPN" "ESD204DQAR"
			(at 171.45 215.9 0)
			(effects
				(font
					(size 1.27 1.27)
					(thickness 0.15)
				)
				(justify left)
			)
		)
		(property "Manufacturer" "Texas Instruments"
			(at 185.42 222.25 0)
			(effects
				(font
					(size 1.27 1.27)
					(thickness 0.15)
				)
				(justify left bottom)
				(hide yes)
			)
		)
		(property "Author" "Antmicro"
			(at 185.42 224.79 0)
			(effects
				(font
					(size 1.27 1.27)
					(thickness 0.15)
				)
				(justify left bottom)
				(hide yes)
			)
		)
		(property "License" "Apache-2.0"
			(at 185.42 227.33 0)
			(effects
				(font
					(size 1.27 1.27)
					(thickness 0.15)
				)
				(justify left bottom)
				(hide yes)
			)
		)
		(pin "3"
		)
		(pin "10"
		)
		(pin "1"
		)
		(pin "4"
		)
		(pin "9"
		)
		(pin "5"
		)
		(pin "7"
		)
		(pin "6"
		)
		(pin "8"
		)
		(pin "2"
		)
		(instances
			(project "OCuLink to 10GbE adapter"
				(path ""
					(reference "D4")
					(unit 1)
				)
			)
		)
	)
	(symbol
		(lib_id "antmicropower:+3V3")
		(at 257.81 95.25 0)
		(unit 1)
		(exclude_from_sim no)
		(in_bom yes)
		(on_board yes)
		(dnp no)
		(fields_autoplaced yes)
		(property "Reference" "#PWR0320"
			(at 273.05 95.25 0)
			(effects
				(font
					(size 1.27 1.27)
					(thickness 0.15)
				)
				(justify left bottom)
				(hide yes)
			)
		)
		(property "Value" "+3V3"
			(at 257.81 90.17 0)
			(effects
				(font
					(size 1.27 1.27)
					(thickness 0.15)
				)
			)
		)
		(property "Footprint" ""
			(at 273.05 102.87 0)
			(effects
				(font
					(size 1.27 1.27)
					(thickness 0.15)
				)
				(justify left bottom)
				(hide yes)
			)
		)
		(property "Datasheet" ""
			(at 273.05 105.41 0)
			(effects
				(font
					(size 1.27 1.27)
					(thickness 0.15)
				)
				(justify left bottom)
				(hide yes)
			)
		)
		(property "Description" ""
			(at 273.05 107.95 0)
			(effects
				(font
					(size 1.27 1.27)
				)
				(justify left bottom)
				(hide yes)
			)
		)
		(property "Author" "Antmicro"
			(at 273.05 97.79 0)
			(effects
				(font
					(size 1.27 1.27)
					(thickness 0.15)
				)
				(justify left bottom)
				(hide yes)
			)
		)
		(property "License" "Apache-2.0"
			(at 273.05 100.33 0)
			(effects
				(font
					(size 1.27 1.27)
					(thickness 0.15)
				)
				(justify left bottom)
				(hide yes)
			)
		)
		(pin "1"
		)
		(instances
			(project ""
				(path ""
					(reference "#PWR0320")
					(unit 1)
				)
			)
		)
	)
	(symbol
		(lib_id "antmicropower:GND")
		(at 259.08 222.25 0)
		(unit 1)
		(exclude_from_sim no)
		(in_bom yes)
		(on_board yes)
		(dnp no)
		(property "Reference" "#PWR0324"
			(at 267.97 224.79 0)
			(effects
				(font
					(size 1.27 1.27)
					(thickness 0.15)
				)
				(justify left bottom)
				(hide yes)
			)
		)
		(property "Value" "GND"
			(at 259.08 226.06 0)
			(effects
				(font
					(size 1.27 1.27)
					(thickness 0.15)
				)
			)
		)
		(property "Footprint" ""
			(at 267.97 229.87 0)
			(effects
				(font
					(size 1.27 1.27)
					(thickness 0.15)
				)
				(justify left bottom)
				(hide yes)
			)
		)
		(property "Datasheet" ""
			(at 267.97 234.95 0)
			(effects
				(font
					(size 1.27 1.27)
					(thickness 0.15)
				)
				(justify left bottom)
				(hide yes)
			)
		)
		(property "Description" ""
			(at 259.08 222.25 0)
			(effects
				(font
					(size 1.27 1.27)
				)
				(hide yes)
			)
		)
		(property "Author" "Antmicro"
			(at 267.97 229.87 0)
			(effects
				(font
					(size 1.27 1.27)
					(thickness 0.15)
				)
				(justify left bottom)
				(hide yes)
			)
		)
		(property "License" "Apache-2.0"
			(at 267.97 232.41 0)
			(effects
				(font
					(size 1.27 1.27)
					(thickness 0.15)
				)
				(justify left bottom)
				(hide yes)
			)
		)
		(pin "1"
		)
		(instances
			(project "OCuLink to 10GbE adapter"
				(path ""
					(reference "#PWR0324")
					(unit 1)
				)
			)
		)
	)
	(symbol
		(lib_id "antmicropower:GND")
		(at 223.52 86.36 0)
		(unit 1)
		(exclude_from_sim no)
		(in_bom yes)
		(on_board yes)
		(dnp no)
		(property "Reference" "#PWR0311"
			(at 232.41 88.9 0)
			(effects
				(font
					(size 1.27 1.27)
					(thickness 0.15)
				)
				(justify left bottom)
				(hide yes)
			)
		)
		(property "Value" "GND"
			(at 223.52 90.17 0)
			(effects
				(font
					(size 1.27 1.27)
					(thickness 0.15)
				)
			)
		)
		(property "Footprint" ""
			(at 232.41 93.98 0)
			(effects
				(font
					(size 1.27 1.27)
					(thickness 0.15)
				)
				(justify left bottom)
				(hide yes)
			)
		)
		(property "Datasheet" ""
			(at 232.41 99.06 0)
			(effects
				(font
					(size 1.27 1.27)
					(thickness 0.15)
				)
				(justify left bottom)
				(hide yes)
			)
		)
		(property "Description" ""
			(at 223.52 86.36 0)
			(effects
				(font
					(size 1.27 1.27)
				)
				(hide yes)
			)
		)
		(property "Author" "Antmicro"
			(at 232.41 93.98 0)
			(effects
				(font
					(size 1.27 1.27)
					(thickness 0.15)
				)
				(justify left bottom)
				(hide yes)
			)
		)
		(property "License" "Apache-2.0"
			(at 232.41 96.52 0)
			(effects
				(font
					(size 1.27 1.27)
					(thickness 0.15)
				)
				(justify left bottom)
				(hide yes)
			)
		)
		(pin "1"
		)
		(instances
			(project "oculink-to-10gbe-adapter"
				(path ""
					(reference "#PWR0311")
					(unit 1)
				)
			)
		)
	)
	(symbol
		(lib_id "antmicroTVSDiodes:ESD204DQAR")
		(at 261.62 209.55 0)
		(unit 1)
		(exclude_from_sim no)
		(in_bom yes)
		(on_board yes)
		(dnp no)
		(fields_autoplaced yes)
		(property "Reference" "D6"
			(at 271.78 213.36 0)
			(effects
				(font
					(size 1.27 1.27)
					(thickness 0.15)
				)
				(justify left)
			)
		)
		(property "Value" "ESD204DQAR"
			(at 285.75 214.63 0)
			(effects
				(font
					(size 1.27 1.27)
					(thickness 0.15)
				)
				(justify left bottom)
				(hide yes)
			)
		)
		(property "Footprint" "antmicro-footprints:USON-10_2.5x1mm_P0.5mm"
			(at 285.75 217.17 0)
			(effects
				(font
					(size 1.27 1.27)
					(thickness 0.15)
				)
				(justify left bottom)
				(hide yes)
			)
		)
		(property "Datasheet" "https://www.ti.com/lit/ds/symlink/esd204.pdf?ts=1706004844383&ref_url=https%253A%252F%252Fwww.ti.com%252Finterface%252Fdiodes%252Fesd-protection-diodes%252Fproducts.html"
			(at 285.75 219.71 0)
			(effects
				(font
					(size 1.27 1.27)
					(thickness 0.15)
				)
				(justify left bottom)
				(hide yes)
			)
		)
		(property "Description" "TVS diode array, 30 kV, USON-10, 3.6 V, 0.55 pF"
			(at 285.75 229.87 0)
			(effects
				(font
					(size 1.27 1.27)
				)
				(justify left bottom)
				(hide yes)
			)
		)
		(property "MPN" "ESD204DQAR"
			(at 271.78 215.9 0)
			(effects
				(font
					(size 1.27 1.27)
					(thickness 0.15)
				)
				(justify left)
			)
		)
		(property "Manufacturer" "Texas Instruments"
			(at 285.75 222.25 0)
			(effects
				(font
					(size 1.27 1.27)
					(thickness 0.15)
				)
				(justify left bottom)
				(hide yes)
			)
		)
		(property "Author" "Antmicro"
			(at 285.75 224.79 0)
			(effects
				(font
					(size 1.27 1.27)
					(thickness 0.15)
				)
				(justify left bottom)
				(hide yes)
			)
		)
		(property "License" "Apache-2.0"
			(at 285.75 227.33 0)
			(effects
				(font
					(size 1.27 1.27)
					(thickness 0.15)
				)
				(justify left bottom)
				(hide yes)
			)
		)
		(pin "3"
		)
		(pin "10"
		)
		(pin "1"
		)
		(pin "4"
		)
		(pin "9"
		)
		(pin "5"
		)
		(pin "7"
		)
		(pin "6"
		)
		(pin "8"
		)
		(pin "2"
		)
		(instances
			(project "OCuLink to 10GbE adapter"
				(path ""
					(reference "D6")
					(unit 1)
				)
			)
		)
	)
	(symbol
		(lib_id "antmicroTestPoints:TP_0.75mm_SMD")
		(at 240.03 107.95 90)
		(unit 1)
		(exclude_from_sim no)
		(in_bom no)
		(on_board yes)
		(dnp no)
		(property "Reference" "TP14"
			(at 240.03 102.87 90)
			(effects
				(font
					(size 1.27 1.27)
					(thickness 0.15)
				)
			)
		)
		(property "Value" "TP_0.75mm_SMD"
			(at 243.84 97.79 0)
			(effects
				(font
					(size 1.27 1.27)
					(thickness 0.15)
				)
				(justify left bottom)
				(hide yes)
			)
		)
		(property "Footprint" "antmicro-footprints:TP_SMD_0.75mm"
			(at 246.38 97.79 0)
			(effects
				(font
					(size 1.27 1.27)
					(thickness 0.15)
				)
				(justify left bottom)
				(hide yes)
			)
		)
		(property "Datasheet" ""
			(at 252.73 90.17 0)
			(effects
				(font
					(size 1.27 1.27)
					(thickness 0.15)
				)
				(justify left bottom)
				(hide yes)
			)
		)
		(property "Description" "SMT test point"
			(at 240.03 107.95 0)
			(effects
				(font
					(size 1.27 1.27)
				)
				(hide yes)
			)
		)
		(property "MPN" ""
			(at 251.46 97.155 0)
			(effects
				(font
					(size 1.27 1.27)
					(thickness 0.15)
				)
				(justify left bottom)
				(hide yes)
			)
		)
		(property "Manufacturer" ""
			(at 246.38 97.155 0)
			(effects
				(font
					(size 1.27 1.27)
					(thickness 0.15)
				)
				(justify left bottom)
				(hide yes)
			)
		)
		(property "Author" "Antmicro"
			(at 248.92 97.79 0)
			(effects
				(font
					(size 1.27 1.27)
					(thickness 0.15)
				)
				(justify left bottom)
				(hide yes)
			)
		)
		(property "License" "Apache-2.0"
			(at 251.46 97.79 0)
			(effects
				(font
					(size 1.27 1.27)
					(thickness 0.15)
				)
				(justify left bottom)
				(hide yes)
			)
		)
		(pin "1"
		)
		(instances
			(project ""
				(path ""
					(reference "TP14")
					(unit 1)
				)
			)
		)
	)
	(symbol
		(lib_id "antmicroPciConnectors:OCuLink_x4_Amphenol_G14A421211112HR_CUSTOM_device_side")
		(at 191.77 85.09 0)
		(mirror y)
		(unit 1)
		(exclude_from_sim no)
		(in_bom yes)
		(on_board yes)
		(dnp no)
		(fields_autoplaced yes)
		(property "Reference" "J9"
			(at 179.07 77.47 0)
			(effects
				(font
					(size 1.27 1.27)
					(thickness 0.15)
				)
			)
		)
		(property "Value" "OCuLink_x4_Amphenol_G14A421211112HR_CUSTOM_device_side"
			(at 152.4 97.79 0)
			(effects
				(font
					(size 1.27 1.27)
					(thickness 0.15)
				)
				(justify left bottom)
				(hide yes)
			)
		)
		(property "Footprint" "antmicro-footprints:Amphenol_G14A421211112HR"
			(at 152.4 100.33 0)
			(effects
				(font
					(size 1.27 1.27)
					(thickness 0.15)
				)
				(justify left bottom)
				(hide yes)
			)
		)
		(property "Datasheet" "https://cdn.amphenol-cs.com/media/wysiwyg/files/drawing/g14a421x1bxxxhr.pdf"
			(at 152.4 102.87 0)
			(effects
				(font
					(size 1.27 1.27)
					(thickness 0.15)
				)
				(justify left bottom)
				(hide yes)
			)
		)
		(property "Description" "I/O Connectors OCulink, Receptacle, 0.5mm pitch, 4X, R/A SMT with shell leg SMT type, 30U\" gold plating, LCP, black, T&R packing"
			(at 191.77 85.09 0)
			(effects
				(font
					(size 1.27 1.27)
				)
				(hide yes)
			)
		)
		(property "Manufacturer" "Amphenol"
			(at 152.4 95.25 0)
			(effects
				(font
					(size 1.27 1.27)
					(thickness 0.15)
				)
				(justify left bottom)
				(hide yes)
			)
		)
		(property "MPN" "G14A421211112HR"
			(at 179.07 80.01 0)
			(effects
				(font
					(size 1.27 1.27)
					(thickness 0.15)
				)
			)
		)
		(property "Author" "Antmicro"
			(at 152.4 105.41 0)
			(effects
				(font
					(size 1.27 1.27)
					(thickness 0.15)
				)
				(justify left bottom)
				(hide yes)
			)
		)
		(property "License" "Apache-2.0"
			(at 152.4 107.95 0)
			(effects
				(font
					(size 1.27 1.27)
					(thickness 0.15)
				)
				(justify left bottom)
				(hide yes)
			)
		)
		(pin "A6"
		)
		(pin "B18"
		)
		(pin "A21"
		)
		(pin "A14"
		)
		(pin "B13"
		)
		(pin "A15"
		)
		(pin "B4"
		)
		(pin "A18"
		)
		(pin "A5"
		)
		(pin "B20"
		)
		(pin "B10"
		)
		(pin "A17"
		)
		(pin "B1"
		)
		(pin "A12"
		)
		(pin "A19"
		)
		(pin "A3"
		)
		(pin "A7"
		)
		(pin "A4"
		)
		(pin "A10"
		)
		(pin "B17"
		)
		(pin "A8"
		)
		(pin "A1"
		)
		(pin "B21"
		)
		(pin "A9"
		)
		(pin "A13"
		)
		(pin "B3"
		)
		(pin "B11"
		)
		(pin "B14"
		)
		(pin "B2"
		)
		(pin "A16"
		)
		(pin "A2"
		)
		(pin "B6"
		)
		(pin "B5"
		)
		(pin "B15"
		)
		(pin "A11"
		)
		(pin "A20"
		)
		(pin "SH"
		)
		(pin "B12"
		)
		(pin "B8"
		)
		(pin "B7"
		)
		(pin "B19"
		)
		(pin "B16"
		)
		(pin "B9"
		)
		(instances
			(project ""
				(path ""
					(reference "J9")
					(unit 1)
				)
			)
		)
	)
	(symbol
		(lib_id "antmicropower:GND")
		(at 163.83 179.07 0)
		(unit 1)
		(exclude_from_sim no)
		(in_bom yes)
		(on_board yes)
		(dnp no)
		(property "Reference" "#PWR0321"
			(at 172.72 181.61 0)
			(effects
				(font
					(size 1.27 1.27)
					(thickness 0.15)
				)
				(justify left bottom)
				(hide yes)
			)
		)
		(property "Value" "GND"
			(at 163.83 182.88 0)
			(effects
				(font
					(size 1.27 1.27)
					(thickness 0.15)
				)
			)
		)
		(property "Footprint" ""
			(at 172.72 186.69 0)
			(effects
				(font
					(size 1.27 1.27)
					(thickness 0.15)
				)
				(justify left bottom)
				(hide yes)
			)
		)
		(property "Datasheet" ""
			(at 172.72 191.77 0)
			(effects
				(font
					(size 1.27 1.27)
					(thickness 0.15)
				)
				(justify left bottom)
				(hide yes)
			)
		)
		(property "Description" ""
			(at 163.83 179.07 0)
			(effects
				(font
					(size 1.27 1.27)
				)
				(hide yes)
			)
		)
		(property "Author" "Antmicro"
			(at 172.72 186.69 0)
			(effects
				(font
					(size 1.27 1.27)
					(thickness 0.15)
				)
				(justify left bottom)
				(hide yes)
			)
		)
		(property "License" "Apache-2.0"
			(at 172.72 189.23 0)
			(effects
				(font
					(size 1.27 1.27)
					(thickness 0.15)
				)
				(justify left bottom)
				(hide yes)
			)
		)
		(pin "1"
		)
		(instances
			(project "OCuLink to 10GbE adapter"
				(path ""
					(reference "#PWR0321")
					(unit 1)
				)
			)
		)
	)
	(symbol
		(lib_id "antmicroResistors0402:R_0R_0402")
		(at 207.01 97.79 0)
		(unit 1)
		(exclude_from_sim no)
		(in_bom yes)
		(on_board yes)
		(dnp no)
		(property "Reference" "R163"
			(at 207.01 96.52 0)
			(effects
				(font
					(size 1.27 1.27)
					(thickness 0.15)
				)
				(justify right)
			)
		)
		(property "Value" "R_0R_0402"
			(at 227.33 110.49 0)
			(effects
				(font
					(size 1.27 1.27)
					(thickness 0.15)
				)
				(justify left bottom)
				(hide yes)
			)
		)
		(property "Footprint" "antmicro-footprints:R_0402_1005Metric"
			(at 227.33 113.03 0)
			(effects
				(font
					(size 1.27 1.27)
					(thickness 0.15)
				)
				(justify left bottom)
				(hide yes)
			)
		)
		(property "Datasheet" "https://industrial.panasonic.com/cdbs/www-data/pdf/RDA0000/AOA0000C301.pdf"
			(at 227.33 115.57 0)
			(effects
				(font
					(size 1.27 1.27)
					(thickness 0.15)
				)
				(justify left bottom)
				(hide yes)
			)
		)
		(property "Description" "SMD Chip Resistor, Jumper, 0 ohm, 100 mW, 0402 [1005 Metric], Thick Film, General Purpose"
			(at 207.01 97.79 0)
			(effects
				(font
					(size 1.27 1.27)
				)
				(hide yes)
			)
		)
		(property "MPN" "ERJ2GE0R00X"
			(at 227.33 118.11 0)
			(effects
				(font
					(size 1.27 1.27)
					(thickness 0.15)
				)
				(justify left bottom)
				(hide yes)
			)
		)
		(property "Manufacturer" "Panasonic"
			(at 227.33 120.65 0)
			(effects
				(font
					(size 1.27 1.27)
					(thickness 0.15)
				)
				(justify left bottom)
				(hide yes)
			)
		)
		(property "License" "Apache-2.0"
			(at 227.33 123.19 0)
			(effects
				(font
					(size 1.27 1.27)
					(thickness 0.15)
				)
				(justify left bottom)
				(hide yes)
			)
		)
		(property "Author" "Antmicro"
			(at 227.33 125.73 0)
			(effects
				(font
					(size 1.27 1.27)
					(thickness 0.15)
				)
				(justify left bottom)
				(hide yes)
			)
		)
		(property "Val" "0R"
			(at 212.09 96.52 0)
			(effects
				(font
					(size 1.27 1.27)
					(thickness 0.15)
				)
				(justify left)
			)
		)
		(property "Tolerance" "~"
			(at 227.33 107.95 0)
			(effects
				(font
					(size 1.27 1.27)
				)
				(justify left bottom)
				(hide yes)
			)
		)
		(property "Current" "1A"
			(at 227.33 128.27 0)
			(effects
				(font
					(size 1.27 1.27)
					(thickness 0.15)
				)
				(justify left bottom)
				(hide yes)
			)
		)
		(pin "2"
		)
		(pin "1"
		)
		(instances
			(project "OCuLink to 10GbE adapter"
				(path ""
					(reference "R163")
					(unit 1)
				)
			)
		)
	)
	(symbol
		(lib_id "antmicroResistors0402:R_0R_0402")
		(at 281.94 110.49 0)
		(unit 1)
		(exclude_from_sim no)
		(in_bom yes)
		(on_board yes)
		(dnp no)
		(property "Reference" "R167"
			(at 281.94 109.22 0)
			(effects
				(font
					(size 1.27 1.27)
					(thickness 0.15)
				)
				(justify right)
			)
		)
		(property "Value" "R_0R_0402"
			(at 302.26 123.19 0)
			(effects
				(font
					(size 1.27 1.27)
					(thickness 0.15)
				)
				(justify left bottom)
				(hide yes)
			)
		)
		(property "Footprint" "antmicro-footprints:R_0402_1005Metric"
			(at 302.26 125.73 0)
			(effects
				(font
					(size 1.27 1.27)
					(thickness 0.15)
				)
				(justify left bottom)
				(hide yes)
			)
		)
		(property "Datasheet" "https://industrial.panasonic.com/cdbs/www-data/pdf/RDA0000/AOA0000C301.pdf"
			(at 302.26 128.27 0)
			(effects
				(font
					(size 1.27 1.27)
					(thickness 0.15)
				)
				(justify left bottom)
				(hide yes)
			)
		)
		(property "Description" "SMD Chip Resistor, Jumper, 0 ohm, 100 mW, 0402 [1005 Metric], Thick Film, General Purpose"
			(at 281.94 110.49 0)
			(effects
				(font
					(size 1.27 1.27)
				)
				(hide yes)
			)
		)
		(property "MPN" "ERJ2GE0R00X"
			(at 302.26 130.81 0)
			(effects
				(font
					(size 1.27 1.27)
					(thickness 0.15)
				)
				(justify left bottom)
				(hide yes)
			)
		)
		(property "Manufacturer" "Panasonic"
			(at 302.26 133.35 0)
			(effects
				(font
					(size 1.27 1.27)
					(thickness 0.15)
				)
				(justify left bottom)
				(hide yes)
			)
		)
		(property "License" "Apache-2.0"
			(at 302.26 135.89 0)
			(effects
				(font
					(size 1.27 1.27)
					(thickness 0.15)
				)
				(justify left bottom)
				(hide yes)
			)
		)
		(property "Author" "Antmicro"
			(at 302.26 138.43 0)
			(effects
				(font
					(size 1.27 1.27)
					(thickness 0.15)
				)
				(justify left bottom)
				(hide yes)
			)
		)
		(property "Val" "0R"
			(at 287.02 109.22 0)
			(effects
				(font
					(size 1.27 1.27)
					(thickness 0.15)
				)
				(justify left)
			)
		)
		(property "Tolerance" "~"
			(at 302.26 120.65 0)
			(effects
				(font
					(size 1.27 1.27)
				)
				(justify left bottom)
				(hide yes)
			)
		)
		(property "Current" "1A"
			(at 302.26 140.97 0)
			(effects
				(font
					(size 1.27 1.27)
					(thickness 0.15)
				)
				(justify left bottom)
				(hide yes)
			)
		)
		(pin "2"
		)
		(pin "1"
		)
		(instances
			(project "OCuLink to 10GbE adapter"
				(path ""
					(reference "R167")
					(unit 1)
				)
			)
		)
	)
	(symbol
		(lib_id "antmicroTVSDiodes:ESD204DQAR")
		(at 212.09 209.55 0)
		(unit 1)
		(exclude_from_sim no)
		(in_bom yes)
		(on_board yes)
		(dnp no)
		(fields_autoplaced yes)
		(property "Reference" "D5"
			(at 222.25 213.36 0)
			(effects
				(font
					(size 1.27 1.27)
					(thickness 0.15)
				)
				(justify left)
			)
		)
		(property "Value" "ESD204DQAR"
			(at 236.22 214.63 0)
			(effects
				(font
					(size 1.27 1.27)
					(thickness 0.15)
				)
				(justify left bottom)
				(hide yes)
			)
		)
		(property "Footprint" "antmicro-footprints:USON-10_2.5x1mm_P0.5mm"
			(at 236.22 217.17 0)
			(effects
				(font
					(size 1.27 1.27)
					(thickness 0.15)
				)
				(justify left bottom)
				(hide yes)
			)
		)
		(property "Datasheet" "https://www.ti.com/lit/ds/symlink/esd204.pdf?ts=1706004844383&ref_url=https%253A%252F%252Fwww.ti.com%252Finterface%252Fdiodes%252Fesd-protection-diodes%252Fproducts.html"
			(at 236.22 219.71 0)
			(effects
				(font
					(size 1.27 1.27)
					(thickness 0.15)
				)
				(justify left bottom)
				(hide yes)
			)
		)
		(property "Description" "TVS diode array, 30 kV, USON-10, 3.6 V, 0.55 pF"
			(at 236.22 229.87 0)
			(effects
				(font
					(size 1.27 1.27)
				)
				(justify left bottom)
				(hide yes)
			)
		)
		(property "MPN" "ESD204DQAR"
			(at 222.25 215.9 0)
			(effects
				(font
					(size 1.27 1.27)
					(thickness 0.15)
				)
				(justify left)
			)
		)
		(property "Manufacturer" "Texas Instruments"
			(at 236.22 222.25 0)
			(effects
				(font
					(size 1.27 1.27)
					(thickness 0.15)
				)
				(justify left bottom)
				(hide yes)
			)
		)
		(property "Author" "Antmicro"
			(at 236.22 224.79 0)
			(effects
				(font
					(size 1.27 1.27)
					(thickness 0.15)
				)
				(justify left bottom)
				(hide yes)
			)
		)
		(property "License" "Apache-2.0"
			(at 236.22 227.33 0)
			(effects
				(font
					(size 1.27 1.27)
					(thickness 0.15)
				)
				(justify left bottom)
				(hide yes)
			)
		)
		(pin "3"
		)
		(pin "10"
		)
		(pin "1"
		)
		(pin "4"
		)
		(pin "9"
		)
		(pin "5"
		)
		(pin "7"
		)
		(pin "6"
		)
		(pin "8"
		)
		(pin "2"
		)
		(instances
			(project "OCuLink to 10GbE adapter"
				(path ""
					(reference "D5")
					(unit 1)
				)
			)
		)
	)
	(symbol
		(lib_id "antmicroLEDIndicationDiscrete:LED_G_0603_LG_L29K-G2J1-24-Z")
		(at 223.52 83.82 90)
		(unit 1)
		(exclude_from_sim no)
		(in_bom yes)
		(on_board yes)
		(dnp no)
		(property "Reference" "D15"
			(at 224.79 80.01 90)
			(effects
				(font
					(size 1.27 1.27)
					(thickness 0.15)
				)
				(justify right)
			)
		)
		(property "Value" "LED_G_0603_LG_L29K-G2J1-24-Z"
			(at 231.14 63.5 0)
			(effects
				(font
					(size 1.27 1.27)
					(thickness 0.15)
				)
				(justify left bottom)
				(hide yes)
			)
		)
		(property "Footprint" "antmicro-footprints:LED_0603_1608Metric_G"
			(at 233.68 63.5 0)
			(effects
				(font
					(size 1.27 1.27)
					(thickness 0.15)
				)
				(justify left bottom)
				(hide yes)
			)
		)
		(property "Datasheet" "https://look.ams-osram.com/m/19ee86b3ae0ee95b/original/LG-L29K.pdf"
			(at 236.22 63.5 0)
			(effects
				(font
					(size 1.27 1.27)
					(thickness 0.15)
				)
				(justify left bottom)
				(hide yes)
			)
		)
		(property "Description" "LED, Green, SMD, 0603, 20 mA, 1.7 V, 570 nm"
			(at 223.52 83.82 0)
			(effects
				(font
					(size 1.27 1.27)
				)
				(hide yes)
			)
		)
		(property "MPN" "LG L29K-G2J1-24-Z"
			(at 238.76 63.5 0)
			(effects
				(font
					(size 1.27 1.27)
					(thickness 0.15)
				)
				(justify left bottom)
				(hide yes)
			)
		)
		(property "Manufacturer" "OSRAM"
			(at 241.3 63.5 0)
			(effects
				(font
					(size 1.27 1.27)
					(thickness 0.15)
				)
				(justify left bottom)
				(hide yes)
			)
		)
		(property "Color" "Green"
			(at 224.79 82.5499 90)
			(effects
				(font
					(size 1.27 1.27)
				)
				(justify right)
			)
		)
		(property "Author" "Antmicro"
			(at 243.84 63.5 0)
			(effects
				(font
					(size 1.27 1.27)
					(thickness 0.15)
				)
				(justify left bottom)
				(hide yes)
			)
		)
		(property "License" "Apache-2.0"
			(at 246.38 63.5 0)
			(effects
				(font
					(size 1.27 1.27)
					(thickness 0.15)
				)
				(justify left bottom)
				(hide yes)
			)
		)
		(pin "2"
		)
		(pin "1"
		)
		(instances
			(project "oculink-to-10gbe-adapter"
				(path ""
					(reference "D15")
					(unit 1)
				)
			)
		)
	)
	(symbol
		(lib_id "antmicropower:GND")
		(at 209.55 247.65 0)
		(unit 1)
		(exclude_from_sim no)
		(in_bom yes)
		(on_board yes)
		(dnp no)
		(property "Reference" "#PWR0326"
			(at 218.44 250.19 0)
			(effects
				(font
					(size 1.27 1.27)
					(thickness 0.15)
				)
				(justify left bottom)
				(hide yes)
			)
		)
		(property "Value" "GND"
			(at 209.55 251.46 0)
			(effects
				(font
					(size 1.27 1.27)
					(thickness 0.15)
				)
			)
		)
		(property "Footprint" ""
			(at 218.44 255.27 0)
			(effects
				(font
					(size 1.27 1.27)
					(thickness 0.15)
				)
				(justify left bottom)
				(hide yes)
			)
		)
		(property "Datasheet" ""
			(at 218.44 260.35 0)
			(effects
				(font
					(size 1.27 1.27)
					(thickness 0.15)
				)
				(justify left bottom)
				(hide yes)
			)
		)
		(property "Description" ""
			(at 209.55 247.65 0)
			(effects
				(font
					(size 1.27 1.27)
				)
				(hide yes)
			)
		)
		(property "Author" "Antmicro"
			(at 218.44 255.27 0)
			(effects
				(font
					(size 1.27 1.27)
					(thickness 0.15)
				)
				(justify left bottom)
				(hide yes)
			)
		)
		(property "License" "Apache-2.0"
			(at 218.44 257.81 0)
			(effects
				(font
					(size 1.27 1.27)
					(thickness 0.15)
				)
				(justify left bottom)
				(hide yes)
			)
		)
		(pin "1"
		)
		(instances
			(project "OCuLink to 10GbE adapter"
				(path ""
					(reference "#PWR0326")
					(unit 1)
				)
			)
		)
	)
	(symbol
		(lib_id "antmicroTestPoints:TP_0.75mm_SMD")
		(at 245.11 107.95 90)
		(unit 1)
		(exclude_from_sim no)
		(in_bom no)
		(on_board yes)
		(dnp no)
		(property "Reference" "TP15"
			(at 245.11 102.87 90)
			(effects
				(font
					(size 1.27 1.27)
					(thickness 0.15)
				)
			)
		)
		(property "Value" "TP_0.75mm_SMD"
			(at 248.92 97.79 0)
			(effects
				(font
					(size 1.27 1.27)
					(thickness 0.15)
				)
				(justify left bottom)
				(hide yes)
			)
		)
		(property "Footprint" "antmicro-footprints:TP_SMD_0.75mm"
			(at 251.46 97.79 0)
			(effects
				(font
					(size 1.27 1.27)
					(thickness 0.15)
				)
				(justify left bottom)
				(hide yes)
			)
		)
		(property "Datasheet" ""
			(at 257.81 90.17 0)
			(effects
				(font
					(size 1.27 1.27)
					(thickness 0.15)
				)
				(justify left bottom)
				(hide yes)
			)
		)
		(property "Description" "SMT test point"
			(at 245.11 107.95 0)
			(effects
				(font
					(size 1.27 1.27)
				)
				(hide yes)
			)
		)
		(property "MPN" ""
			(at 256.54 97.155 0)
			(effects
				(font
					(size 1.27 1.27)
					(thickness 0.15)
				)
				(justify left bottom)
				(hide yes)
			)
		)
		(property "Manufacturer" ""
			(at 251.46 97.155 0)
			(effects
				(font
					(size 1.27 1.27)
					(thickness 0.15)
				)
				(justify left bottom)
				(hide yes)
			)
		)
		(property "Author" "Antmicro"
			(at 254 97.79 0)
			(effects
				(font
					(size 1.27 1.27)
					(thickness 0.15)
				)
				(justify left bottom)
				(hide yes)
			)
		)
		(property "License" "Apache-2.0"
			(at 256.54 97.79 0)
			(effects
				(font
					(size 1.27 1.27)
					(thickness 0.15)
				)
				(justify left bottom)
				(hide yes)
			)
		)
		(pin "1"
		)
		(instances
			(project "OCuLink to 10GbE adapter"
				(path ""
					(reference "TP15")
					(unit 1)
				)
			)
		)
	)
	(symbol
		(lib_id "antmicropower:GND")
		(at 259.08 247.65 0)
		(unit 1)
		(exclude_from_sim no)
		(in_bom yes)
		(on_board yes)
		(dnp no)
		(property "Reference" "#PWR0327"
			(at 267.97 250.19 0)
			(effects
				(font
					(size 1.27 1.27)
					(thickness 0.15)
				)
				(justify left bottom)
				(hide yes)
			)
		)
		(property "Value" "GND"
			(at 259.08 251.46 0)
			(effects
				(font
					(size 1.27 1.27)
					(thickness 0.15)
				)
			)
		)
		(property "Footprint" ""
			(at 267.97 255.27 0)
			(effects
				(font
					(size 1.27 1.27)
					(thickness 0.15)
				)
				(justify left bottom)
				(hide yes)
			)
		)
		(property "Datasheet" ""
			(at 267.97 260.35 0)
			(effects
				(font
					(size 1.27 1.27)
					(thickness 0.15)
				)
				(justify left bottom)
				(hide yes)
			)
		)
		(property "Description" ""
			(at 259.08 247.65 0)
			(effects
				(font
					(size 1.27 1.27)
				)
				(hide yes)
			)
		)
		(property "Author" "Antmicro"
			(at 267.97 255.27 0)
			(effects
				(font
					(size 1.27 1.27)
					(thickness 0.15)
				)
				(justify left bottom)
				(hide yes)
			)
		)
		(property "License" "Apache-2.0"
			(at 267.97 257.81 0)
			(effects
				(font
					(size 1.27 1.27)
					(thickness 0.15)
				)
				(justify left bottom)
				(hide yes)
			)
		)
		(pin "1"
		)
		(instances
			(project "OCuLink to 10GbE adapter"
				(path ""
					(reference "#PWR0327")
					(unit 1)
				)
			)
		)
	)
	(symbol
		(lib_id "antmicropower:+3V3_AON")
		(at 194.31 82.55 0)
		(unit 1)
		(exclude_from_sim no)
		(in_bom yes)
		(on_board yes)
		(dnp no)
		(property "Reference" "#PWR099"
			(at 194.31 86.36 0)
			(effects
				(font
					(size 1.27 1.27)
				)
				(hide yes)
			)
		)
		(property "Value" "+3V3_AUX"
			(at 194.31 78.74 0)
			(effects
				(font
					(size 1.27 1.27)
				)
			)
		)
		(property "Footprint" ""
			(at 194.31 82.55 0)
			(effects
				(font
					(size 1.27 1.27)
				)
				(hide yes)
			)
		)
		(property "Datasheet" ""
			(at 194.31 82.55 0)
			(effects
				(font
					(size 1.27 1.27)
				)
				(hide yes)
			)
		)
		(property "Description" ""
			(at 194.31 88.9 0)
			(effects
				(font
					(size 1.27 1.27)
				)
				(justify left bottom)
				(hide yes)
			)
		)
		(pin "1"
		)
		(instances
			(project ""
				(path ""
					(reference "#PWR099")
					(unit 1)
				)
			)
		)
	)
	(symbol
		(lib_id "antmicroTVSDiodes:ESD204DQAR")
		(at 161.29 234.95 0)
		(unit 1)
		(exclude_from_sim no)
		(in_bom yes)
		(on_board yes)
		(dnp no)
		(fields_autoplaced yes)
		(property "Reference" "D7"
			(at 171.45 238.76 0)
			(effects
				(font
					(size 1.27 1.27)
					(thickness 0.15)
				)
				(justify left)
			)
		)
		(property "Value" "ESD204DQAR"
			(at 185.42 240.03 0)
			(effects
				(font
					(size 1.27 1.27)
					(thickness 0.15)
				)
				(justify left bottom)
				(hide yes)
			)
		)
		(property "Footprint" "antmicro-footprints:USON-10_2.5x1mm_P0.5mm"
			(at 185.42 242.57 0)
			(effects
				(font
					(size 1.27 1.27)
					(thickness 0.15)
				)
				(justify left bottom)
				(hide yes)
			)
		)
		(property "Datasheet" "https://www.ti.com/lit/ds/symlink/esd204.pdf?ts=1706004844383&ref_url=https%253A%252F%252Fwww.ti.com%252Finterface%252Fdiodes%252Fesd-protection-diodes%252Fproducts.html"
			(at 185.42 245.11 0)
			(effects
				(font
					(size 1.27 1.27)
					(thickness 0.15)
				)
				(justify left bottom)
				(hide yes)
			)
		)
		(property "Description" "TVS diode array, 30 kV, USON-10, 3.6 V, 0.55 pF"
			(at 185.42 255.27 0)
			(effects
				(font
					(size 1.27 1.27)
				)
				(justify left bottom)
				(hide yes)
			)
		)
		(property "MPN" "ESD204DQAR"
			(at 171.45 241.3 0)
			(effects
				(font
					(size 1.27 1.27)
					(thickness 0.15)
				)
				(justify left)
			)
		)
		(property "Manufacturer" "Texas Instruments"
			(at 185.42 247.65 0)
			(effects
				(font
					(size 1.27 1.27)
					(thickness 0.15)
				)
				(justify left bottom)
				(hide yes)
			)
		)
		(property "Author" "Antmicro"
			(at 185.42 250.19 0)
			(effects
				(font
					(size 1.27 1.27)
					(thickness 0.15)
				)
				(justify left bottom)
				(hide yes)
			)
		)
		(property "License" "Apache-2.0"
			(at 185.42 252.73 0)
			(effects
				(font
					(size 1.27 1.27)
					(thickness 0.15)
				)
				(justify left bottom)
				(hide yes)
			)
		)
		(pin "3"
		)
		(pin "10"
		)
		(pin "1"
		)
		(pin "4"
		)
		(pin "9"
		)
		(pin "5"
		)
		(pin "7"
		)
		(pin "6"
		)
		(pin "8"
		)
		(pin "2"
		)
		(instances
			(project ""
				(path ""
					(reference "D7")
					(unit 1)
				)
			)
		)
	)
	(symbol
		(lib_id "antmicroResistors0402:R_10k_0402")
		(at 266.7 105.41 90)
		(unit 1)
		(exclude_from_sim no)
		(in_bom no)
		(on_board yes)
		(dnp yes)
		(property "Reference" "R165"
			(at 267.97 101.6 90)
			(effects
				(font
					(size 1.27 1.27)
					(thickness 0.15)
				)
				(justify right)
			)
		)
		(property "Value" "R_10k_0402"
			(at 279.4 85.09 0)
			(effects
				(font
					(size 1.27 1.27)
					(thickness 0.15)
				)
				(justify left bottom)
				(hide yes)
			)
		)
		(property "Footprint" "antmicro-footprints:R_0402_1005Metric"
			(at 281.94 85.09 0)
			(effects
				(font
					(size 1.27 1.27)
					(thickness 0.15)
				)
				(justify left bottom)
				(hide yes)
			)
		)
		(property "Datasheet" "https://www.bourns.com/docs/product-datasheets/cr.pdf"
			(at 284.48 85.09 0)
			(effects
				(font
					(size 1.27 1.27)
					(thickness 0.15)
				)
				(justify left bottom)
				(hide yes)
			)
		)
		(property "Description" "SMD Chip Resistor, 10 kohm, ± 1%, 62.5 mW, 0402 [1005 Metric], Thick Film, General Purpose"
			(at 297.18 85.09 0)
			(effects
				(font
					(size 1.27 1.27)
				)
				(justify left bottom)
				(hide yes)
			)
		)
		(property "MPN" "CR0402-FX-1002GLF"
			(at 287.02 85.09 0)
			(effects
				(font
					(size 1.27 1.27)
					(thickness 0.15)
				)
				(justify left bottom)
				(hide yes)
			)
		)
		(property "Manufacturer" "Bourns"
			(at 289.56 85.09 0)
			(effects
				(font
					(size 1.27 1.27)
					(thickness 0.15)
				)
				(justify left bottom)
				(hide yes)
			)
		)
		(property "License" "Apache-2.0"
			(at 292.1 85.09 0)
			(effects
				(font
					(size 1.27 1.27)
					(thickness 0.15)
				)
				(justify left bottom)
				(hide yes)
			)
		)
		(property "Author" "Antmicro"
			(at 294.64 85.09 0)
			(effects
				(font
					(size 1.27 1.27)
					(thickness 0.15)
				)
				(justify left bottom)
				(hide yes)
			)
		)
		(property "Val" "10k"
			(at 267.97 104.14 90)
			(effects
				(font
					(size 1.27 1.27)
					(thickness 0.15)
				)
				(justify right)
			)
		)
		(property "Tolerance" "1%"
			(at 276.86 85.09 0)
			(effects
				(font
					(size 1.27 1.27)
				)
				(justify left bottom)
				(hide yes)
			)
		)
		(pin "2"
		)
		(pin "1"
		)
		(instances
			(project "OCuLink to 10GbE adapter"
				(path ""
					(reference "R165")
					(unit 1)
				)
			)
		)
	)
	(symbol
		(lib_id "antmicropower:GND")
		(at 209.55 222.25 0)
		(unit 1)
		(exclude_from_sim no)
		(in_bom yes)
		(on_board yes)
		(dnp no)
		(property "Reference" "#PWR0323"
			(at 218.44 224.79 0)
			(effects
				(font
					(size 1.27 1.27)
					(thickness 0.15)
				)
				(justify left bottom)
				(hide yes)
			)
		)
		(property "Value" "GND"
			(at 209.55 226.06 0)
			(effects
				(font
					(size 1.27 1.27)
					(thickness 0.15)
				)
			)
		)
		(property "Footprint" ""
			(at 218.44 229.87 0)
			(effects
				(font
					(size 1.27 1.27)
					(thickness 0.15)
				)
				(justify left bottom)
				(hide yes)
			)
		)
		(property "Datasheet" ""
			(at 218.44 234.95 0)
			(effects
				(font
					(size 1.27 1.27)
					(thickness 0.15)
				)
				(justify left bottom)
				(hide yes)
			)
		)
		(property "Description" ""
			(at 209.55 222.25 0)
			(effects
				(font
					(size 1.27 1.27)
				)
				(hide yes)
			)
		)
		(property "Author" "Antmicro"
			(at 218.44 229.87 0)
			(effects
				(font
					(size 1.27 1.27)
					(thickness 0.15)
				)
				(justify left bottom)
				(hide yes)
			)
		)
		(property "License" "Apache-2.0"
			(at 218.44 232.41 0)
			(effects
				(font
					(size 1.27 1.27)
					(thickness 0.15)
				)
				(justify left bottom)
				(hide yes)
			)
		)
		(pin "1"
		)
		(instances
			(project "OCuLink to 10GbE adapter"
				(path ""
					(reference "#PWR0323")
					(unit 1)
				)
			)
		)
	)
	(symbol
		(lib_id "antmicropower:GND")
		(at 158.75 247.65 0)
		(unit 1)
		(exclude_from_sim no)
		(in_bom yes)
		(on_board yes)
		(dnp no)
		(property "Reference" "#PWR0325"
			(at 167.64 250.19 0)
			(effects
				(font
					(size 1.27 1.27)
					(thickness 0.15)
				)
				(justify left bottom)
				(hide yes)
			)
		)
		(property "Value" "GND"
			(at 158.75 251.46 0)
			(effects
				(font
					(size 1.27 1.27)
					(thickness 0.15)
				)
			)
		)
		(property "Footprint" ""
			(at 167.64 255.27 0)
			(effects
				(font
					(size 1.27 1.27)
					(thickness 0.15)
				)
				(justify left bottom)
				(hide yes)
			)
		)
		(property "Datasheet" ""
			(at 167.64 260.35 0)
			(effects
				(font
					(size 1.27 1.27)
					(thickness 0.15)
				)
				(justify left bottom)
				(hide yes)
			)
		)
		(property "Description" ""
			(at 158.75 247.65 0)
			(effects
				(font
					(size 1.27 1.27)
				)
				(hide yes)
			)
		)
		(property "Author" "Antmicro"
			(at 167.64 255.27 0)
			(effects
				(font
					(size 1.27 1.27)
					(thickness 0.15)
				)
				(justify left bottom)
				(hide yes)
			)
		)
		(property "License" "Apache-2.0"
			(at 167.64 257.81 0)
			(effects
				(font
					(size 1.27 1.27)
					(thickness 0.15)
				)
				(justify left bottom)
				(hide yes)
			)
		)
		(pin "1"
		)
		(instances
			(project "OCuLink to 10GbE adapter"
				(path ""
					(reference "#PWR0325")
					(unit 1)
				)
			)
		)
	)
	(symbol
		(lib_id "antmicroResistors0402:R_0R_0402")
		(at 281.94 113.03 0)
		(unit 1)
		(exclude_from_sim no)
		(in_bom yes)
		(on_board yes)
		(dnp no)
		(property "Reference" "R168"
			(at 281.94 111.76 0)
			(effects
				(font
					(size 1.27 1.27)
					(thickness 0.15)
				)
				(justify right)
			)
		)
		(property "Value" "R_0R_0402"
			(at 302.26 125.73 0)
			(effects
				(font
					(size 1.27 1.27)
					(thickness 0.15)
				)
				(justify left bottom)
				(hide yes)
			)
		)
		(property "Footprint" "antmicro-footprints:R_0402_1005Metric"
			(at 302.26 128.27 0)
			(effects
				(font
					(size 1.27 1.27)
					(thickness 0.15)
				)
				(justify left bottom)
				(hide yes)
			)
		)
		(property "Datasheet" "https://industrial.panasonic.com/cdbs/www-data/pdf/RDA0000/AOA0000C301.pdf"
			(at 302.26 130.81 0)
			(effects
				(font
					(size 1.27 1.27)
					(thickness 0.15)
				)
				(justify left bottom)
				(hide yes)
			)
		)
		(property "Description" "SMD Chip Resistor, Jumper, 0 ohm, 100 mW, 0402 [1005 Metric], Thick Film, General Purpose"
			(at 281.94 113.03 0)
			(effects
				(font
					(size 1.27 1.27)
				)
				(hide yes)
			)
		)
		(property "MPN" "ERJ2GE0R00X"
			(at 302.26 133.35 0)
			(effects
				(font
					(size 1.27 1.27)
					(thickness 0.15)
				)
				(justify left bottom)
				(hide yes)
			)
		)
		(property "Manufacturer" "Panasonic"
			(at 302.26 135.89 0)
			(effects
				(font
					(size 1.27 1.27)
					(thickness 0.15)
				)
				(justify left bottom)
				(hide yes)
			)
		)
		(property "License" "Apache-2.0"
			(at 302.26 138.43 0)
			(effects
				(font
					(size 1.27 1.27)
					(thickness 0.15)
				)
				(justify left bottom)
				(hide yes)
			)
		)
		(property "Author" "Antmicro"
			(at 302.26 140.97 0)
			(effects
				(font
					(size 1.27 1.27)
					(thickness 0.15)
				)
				(justify left bottom)
				(hide yes)
			)
		)
		(property "Val" "0R"
			(at 287.02 111.76 0)
			(effects
				(font
					(size 1.27 1.27)
					(thickness 0.15)
				)
				(justify left)
			)
		)
		(property "Tolerance" "~"
			(at 302.26 123.19 0)
			(effects
				(font
					(size 1.27 1.27)
				)
				(justify left bottom)
				(hide yes)
			)
		)
		(property "Current" "1A"
			(at 302.26 143.51 0)
			(effects
				(font
					(size 1.27 1.27)
					(thickness 0.15)
				)
				(justify left bottom)
				(hide yes)
			)
		)
		(pin "2"
		)
		(pin "1"
		)
		(instances
			(project "OCuLink to 10GbE adapter"
				(path ""
					(reference "R168")
					(unit 1)
				)
			)
		)
	)
	(symbol
		(lib_id "antmicroTestPoints:TP_0.75mm_SMD")
		(at 250.19 107.95 90)
		(unit 1)
		(exclude_from_sim no)
		(in_bom no)
		(on_board yes)
		(dnp no)
		(property "Reference" "TP16"
			(at 250.19 102.87 90)
			(effects
				(font
					(size 1.27 1.27)
					(thickness 0.15)
				)
			)
		)
		(property "Value" "TP_0.75mm_SMD"
			(at 254 97.79 0)
			(effects
				(font
					(size 1.27 1.27)
					(thickness 0.15)
				)
				(justify left bottom)
				(hide yes)
			)
		)
		(property "Footprint" "antmicro-footprints:TP_SMD_0.75mm"
			(at 256.54 97.79 0)
			(effects
				(font
					(size 1.27 1.27)
					(thickness 0.15)
				)
				(justify left bottom)
				(hide yes)
			)
		)
		(property "Datasheet" ""
			(at 262.89 90.17 0)
			(effects
				(font
					(size 1.27 1.27)
					(thickness 0.15)
				)
				(justify left bottom)
				(hide yes)
			)
		)
		(property "Description" "SMT test point"
			(at 250.19 107.95 0)
			(effects
				(font
					(size 1.27 1.27)
				)
				(hide yes)
			)
		)
		(property "MPN" ""
			(at 261.62 97.155 0)
			(effects
				(font
					(size 1.27 1.27)
					(thickness 0.15)
				)
				(justify left bottom)
				(hide yes)
			)
		)
		(property "Manufacturer" ""
			(at 256.54 97.155 0)
			(effects
				(font
					(size 1.27 1.27)
					(thickness 0.15)
				)
				(justify left bottom)
				(hide yes)
			)
		)
		(property "Author" "Antmicro"
			(at 259.08 97.79 0)
			(effects
				(font
					(size 1.27 1.27)
					(thickness 0.15)
				)
				(justify left bottom)
				(hide yes)
			)
		)
		(property "License" "Apache-2.0"
			(at 261.62 97.79 0)
			(effects
				(font
					(size 1.27 1.27)
					(thickness 0.15)
				)
				(justify left bottom)
				(hide yes)
			)
		)
		(pin "1"
		)
		(instances
			(project "OCuLink to 10GbE adapter"
				(path ""
					(reference "TP16")
					(unit 1)
				)
			)
		)
	)
)
